G04 ================== begin FILE IDENTIFICATION RECORD ==================*
G04 Layout Name:  D:/<user>/Wistron_project/16317-1/gbr/16317-1.brd*
G04 Film Name:    SE_REF_L8*
G04 File Format:  Gerber RS274X*
G04 File Origin:  Cadence Allegro 16.5-S056*
G04 Origin Date:  Fri Jun 09 15:54:16 2017*
G04 *
G04 Layer:  BOARD GEOMETRY/SE_REF_L8_TBL*
G04 Layer:  BOARD GEOMETRY/SE_REF_L8_BOTTOM*
G04 Layer:  BOARD GEOMETRY/PANEL_OUTLINE*
G04 *
G04 Offset:    (0.00 0.00)*
G04 Mirror:    No*
G04 Mode:      Positive*
G04 Rotation:  0*
G04 FullContactRelief:  No*
G04 UndefLineWidth:     6.00*
G04 ================== end FILE IDENTIFICATION RECORD ====================*
%FSLAX35Y35*MOIN*%
%IR0*IPPOS*OFA0.00000B0.00000*MIA0B0*SFA1.00000B1.00000*%
%ADD10C,.02*%
%ADD11C,.006*%
%ADD12C,.00675*%
G75*
%LPD*%
G75*
G54D10*
G01X1985143Y1416035D02*
X2702643D01*
G01X1985143Y1485335D02*
Y1416035D01*
G01Y1485335D02*
X2702643D01*
G01X1985143Y1450685D02*
X2702643D01*
G01X2160143Y1485335D02*
Y1416035D01*
G01X2387643Y1485335D02*
Y1416035D01*
G01X2492643Y1485335D02*
Y1416035D01*
G01X2702643Y1485335D02*
Y1416035D01*
G54D11*
G01X6250Y-33194D02*
Y-50694D01*
G01X1228Y-33194D02*
X11272D01*
G01X20038Y-50694D02*
Y-33194D01*
G01Y-41652D02*
X21130Y-40194D01*
X22222Y-39319D01*
X23968Y-39028D01*
X25278Y-39319D01*
X26807Y-40486D01*
X27462Y-42236D01*
Y-50694D01*
G01X41250Y-39028D02*
Y-50694D01*
G01Y-34361D02*
X40813Y-34069D01*
Y-33486D01*
X41250Y-33194D01*
X41687Y-33486D01*
Y-34069D01*
X41250Y-34361D01*
G01X55475Y-48653D02*
X56567Y-49819D01*
X58095Y-50694D01*
X59405D01*
X60715Y-50111D01*
X61588Y-49236D01*
X62025Y-48070D01*
X61807Y-46319D01*
X60933Y-45444D01*
X57003Y-43694D01*
X56130Y-41652D01*
X56567Y-40194D01*
X57440Y-39319D01*
X58750Y-39028D01*
X60060Y-39319D01*
X61370Y-40194D01*
G01X90693Y-55069D02*
X92222Y-56236D01*
X93968Y-56527D01*
X95496Y-56236D01*
X96807Y-54778D01*
X97680Y-52736D01*
Y-39028D01*
G01Y-41361D02*
X96807Y-40194D01*
X95496Y-39319D01*
X93968Y-39028D01*
X92222Y-39611D01*
X91130Y-40777D01*
X90256Y-42819D01*
X89820Y-44861D01*
X90038Y-46611D01*
X90912Y-48653D01*
X92222Y-50111D01*
X93968Y-50694D01*
X95278Y-50402D01*
X96807Y-49236D01*
X97680Y-48070D01*
G01X107975Y-42819D02*
X114962D01*
X114307Y-40777D01*
X113215Y-39611D01*
X111687Y-39028D01*
X110158Y-39319D01*
X108848Y-40194D01*
X107975Y-42236D01*
X107538Y-43986D01*
Y-45736D01*
X107975Y-47486D01*
X109067Y-49236D01*
X110377Y-50402D01*
X111905Y-50694D01*
X113433Y-50111D01*
X114962Y-48361D01*
G01X125693Y-50694D02*
Y-39028D01*
G01Y-41361D02*
X126785Y-40194D01*
X127877Y-39319D01*
X129405Y-39028D01*
X130496Y-39319D01*
X131807Y-40194D01*
G01X142320Y-50694D02*
Y-33194D01*
G01Y-41944D02*
X143412Y-40194D01*
X144722Y-39319D01*
X146032Y-39028D01*
X147996Y-39611D01*
X149307Y-40777D01*
X150180Y-42819D01*
Y-45152D01*
X149743Y-47486D01*
X148870Y-49236D01*
X147342Y-50402D01*
X146032Y-50694D01*
X144722Y-50402D01*
X143412Y-49528D01*
X142320Y-48070D01*
G01X160475Y-42819D02*
X167462D01*
X166807Y-40777D01*
X165715Y-39611D01*
X164187Y-39028D01*
X162658Y-39319D01*
X161348Y-40194D01*
X160475Y-42236D01*
X160038Y-43986D01*
Y-45736D01*
X160475Y-47486D01*
X161567Y-49236D01*
X162877Y-50402D01*
X164405Y-50694D01*
X165933Y-50111D01*
X167462Y-48361D01*
G01X178193Y-50694D02*
Y-39028D01*
G01Y-41361D02*
X179285Y-40194D01*
X180377Y-39319D01*
X181905Y-39028D01*
X182996Y-39319D01*
X184307Y-40194D01*
G01X216250Y-39028D02*
Y-50694D01*
G01Y-34361D02*
X215813Y-34069D01*
Y-33486D01*
X216250Y-33194D01*
X216687Y-33486D01*
Y-34069D01*
X216250Y-34361D01*
G01X230475Y-48653D02*
X231567Y-49819D01*
X233095Y-50694D01*
X234405D01*
X235715Y-50111D01*
X236588Y-49236D01*
X237025Y-48070D01*
X236807Y-46319D01*
X235933Y-45444D01*
X232003Y-43694D01*
X231130Y-41652D01*
X231567Y-40194D01*
X232440Y-39319D01*
X233750Y-39028D01*
X235060Y-39319D01*
X236370Y-40194D01*
G01X265256Y-55069D02*
X266785Y-56236D01*
X268095Y-56527D01*
X269842Y-55944D01*
X271152Y-54486D01*
X271807Y-51860D01*
Y-39028D01*
G01Y-34361D02*
X271370Y-34069D01*
Y-33486D01*
X271807Y-33194D01*
X272243Y-33486D01*
Y-34069D01*
X271807Y-34361D01*
G01X282538Y-39028D02*
Y-47194D01*
X283412Y-49236D01*
X284722Y-50402D01*
X286250Y-50694D01*
X287778Y-50402D01*
X289088Y-49236D01*
X289962Y-47194D01*
G01Y-50694D02*
Y-39028D01*
G01X300475Y-48653D02*
X301567Y-49819D01*
X303095Y-50694D01*
X304405D01*
X305715Y-50111D01*
X306588Y-49236D01*
X307025Y-48070D01*
X306807Y-46319D01*
X305933Y-45444D01*
X302003Y-43694D01*
X301130Y-41652D01*
X301567Y-40194D01*
X302440Y-39319D01*
X303750Y-39028D01*
X305060Y-39319D01*
X306370Y-40194D01*
G01X321250Y-33194D02*
Y-50694D01*
G01X318193Y-39028D02*
X324307D01*
G01X354940Y-50694D02*
Y-35819D01*
X355377Y-34361D01*
X356250Y-33486D01*
X357560Y-33194D01*
X358870Y-33777D01*
X359525Y-35236D01*
G01X356905Y-40194D02*
X352538D01*
G01X373750Y-50694D02*
X372440Y-50402D01*
X371130Y-49236D01*
X370256Y-47194D01*
X369820Y-44861D01*
X370256Y-42527D01*
X371130Y-40486D01*
X372440Y-39319D01*
X373750Y-39028D01*
X375060Y-39319D01*
X376370Y-40486D01*
X377243Y-42527D01*
X377462Y-44861D01*
X377243Y-47194D01*
X376370Y-49236D01*
X375060Y-50402D01*
X373750Y-50694D01*
G01X388193D02*
Y-39028D01*
G01Y-41361D02*
X389285Y-40194D01*
X390377Y-39319D01*
X391905Y-39028D01*
X392996Y-39319D01*
X394307Y-40194D01*
G01X421665Y-55944D02*
X422975Y-56527D01*
X424722Y-55944D01*
X425813Y-54778D01*
X426687Y-53319D01*
X427996Y-48653D01*
X430835Y-39028D01*
G01X423848D02*
X427996Y-48653D01*
G01X443750Y-50694D02*
X442440Y-50402D01*
X441130Y-49236D01*
X440256Y-47194D01*
X439820Y-44861D01*
X440256Y-42527D01*
X441130Y-40486D01*
X442440Y-39319D01*
X443750Y-39028D01*
X445060Y-39319D01*
X446370Y-40486D01*
X447243Y-42527D01*
X447462Y-44861D01*
X447243Y-47194D01*
X446370Y-49236D01*
X445060Y-50402D01*
X443750Y-50694D01*
G01X457538Y-39028D02*
Y-47194D01*
X458412Y-49236D01*
X459722Y-50402D01*
X461250Y-50694D01*
X462778Y-50402D01*
X464088Y-49236D01*
X464962Y-47194D01*
G01Y-50694D02*
Y-39028D01*
G01X475693Y-50694D02*
Y-39028D01*
G01Y-41361D02*
X476785Y-40194D01*
X477877Y-39319D01*
X479405Y-39028D01*
X480496Y-39319D01*
X481807Y-40194D01*
G01X510693Y-50694D02*
Y-39028D01*
G01Y-41361D02*
X511785Y-40194D01*
X512877Y-39319D01*
X514405Y-39028D01*
X515496Y-39319D01*
X516807Y-40194D01*
G01X527975Y-42819D02*
X534962D01*
X534307Y-40777D01*
X533215Y-39611D01*
X531687Y-39028D01*
X530158Y-39319D01*
X528848Y-40194D01*
X527975Y-42236D01*
X527538Y-43986D01*
Y-45736D01*
X527975Y-47486D01*
X529067Y-49236D01*
X530377Y-50402D01*
X531905Y-50694D01*
X533433Y-50111D01*
X534962Y-48361D01*
G01X547440Y-50694D02*
Y-35819D01*
X547877Y-34361D01*
X548750Y-33486D01*
X550060Y-33194D01*
X551370Y-33777D01*
X552025Y-35236D01*
G01X549405Y-40194D02*
X545038D01*
G01X562975Y-42819D02*
X569962D01*
X569307Y-40777D01*
X568215Y-39611D01*
X566687Y-39028D01*
X565158Y-39319D01*
X563848Y-40194D01*
X562975Y-42236D01*
X562538Y-43986D01*
Y-45736D01*
X562975Y-47486D01*
X564067Y-49236D01*
X565377Y-50402D01*
X566905Y-50694D01*
X568433Y-50111D01*
X569962Y-48361D01*
G01X580693Y-50694D02*
Y-39028D01*
G01Y-41361D02*
X581785Y-40194D01*
X582877Y-39319D01*
X584405Y-39028D01*
X585496Y-39319D01*
X586807Y-40194D01*
G01X597975Y-42819D02*
X604962D01*
X604307Y-40777D01*
X603215Y-39611D01*
X601687Y-39028D01*
X600158Y-39319D01*
X598848Y-40194D01*
X597975Y-42236D01*
X597538Y-43986D01*
Y-45736D01*
X597975Y-47486D01*
X599067Y-49236D01*
X600377Y-50402D01*
X601905Y-50694D01*
X603433Y-50111D01*
X604962Y-48361D01*
G01X615038Y-50694D02*
Y-39028D01*
G01Y-41944D02*
X615912Y-40486D01*
X617222Y-39319D01*
X618968Y-39028D01*
X620496Y-39319D01*
X621807Y-40486D01*
X622462Y-42527D01*
Y-50694D01*
G01X639743Y-40486D02*
X638215Y-39319D01*
X636905Y-39028D01*
X635158Y-39611D01*
X633848Y-40777D01*
X632975Y-42819D01*
X632756Y-44861D01*
X632975Y-46903D01*
X633848Y-48653D01*
X635158Y-50111D01*
X636905Y-50694D01*
X638433Y-50111D01*
X639743Y-48944D01*
G01X650475Y-42819D02*
X657462D01*
X656807Y-40777D01*
X655715Y-39611D01*
X654187Y-39028D01*
X652658Y-39319D01*
X651348Y-40194D01*
X650475Y-42236D01*
X650038Y-43986D01*
Y-45736D01*
X650475Y-47486D01*
X651567Y-49236D01*
X652877Y-50402D01*
X654405Y-50694D01*
X655933Y-50111D01*
X657462Y-48361D01*
G01X688750Y-33194D02*
Y-50694D01*
G01X685693Y-39028D02*
X691807D01*
G01X706250Y-50694D02*
X704940Y-50402D01*
X703630Y-49236D01*
X702756Y-47194D01*
X702320Y-44861D01*
X702756Y-42527D01*
X703630Y-40486D01*
X704940Y-39319D01*
X706250Y-39028D01*
X707560Y-39319D01*
X708870Y-40486D01*
X709743Y-42527D01*
X709962Y-44861D01*
X709743Y-47194D01*
X708870Y-49236D01*
X707560Y-50402D01*
X706250Y-50694D01*
G01X739940D02*
Y-35819D01*
X740377Y-34361D01*
X741250Y-33486D01*
X742560Y-33194D01*
X743870Y-33777D01*
X744525Y-35236D01*
G01X741905Y-40194D02*
X737538D01*
G01X758750Y-39028D02*
Y-50694D01*
G01Y-34361D02*
X758313Y-34069D01*
Y-33486D01*
X758750Y-33194D01*
X759187Y-33486D01*
Y-34069D01*
X758750Y-34361D01*
G01X772538Y-50694D02*
Y-39028D01*
G01Y-41944D02*
X773412Y-40486D01*
X774722Y-39319D01*
X776468Y-39028D01*
X777996Y-39319D01*
X779307Y-40486D01*
X779962Y-42527D01*
Y-50694D01*
G01X797680Y-33194D02*
Y-50694D01*
G01Y-48070D02*
X796807Y-49528D01*
X795496Y-50402D01*
X793968Y-50694D01*
X792222Y-50111D01*
X790912Y-48653D01*
X790038Y-46903D01*
X789820Y-44861D01*
X790038Y-42819D01*
X790912Y-41069D01*
X792222Y-39611D01*
X793968Y-39028D01*
X795496Y-39319D01*
X796588Y-39903D01*
X797680Y-41069D01*
G01X828750Y-33194D02*
Y-50694D01*
G01X825693Y-39028D02*
X831807D01*
G01X842538Y-50694D02*
Y-33194D01*
G01Y-41652D02*
X843630Y-40194D01*
X844722Y-39319D01*
X846468Y-39028D01*
X847778Y-39319D01*
X849307Y-40486D01*
X849962Y-42236D01*
Y-50694D01*
G01X860475Y-42819D02*
X867462D01*
X866807Y-40777D01*
X865715Y-39611D01*
X864187Y-39028D01*
X862658Y-39319D01*
X861348Y-40194D01*
X860475Y-42236D01*
X860038Y-43986D01*
Y-45736D01*
X860475Y-47486D01*
X861567Y-49236D01*
X862877Y-50402D01*
X864405Y-50694D01*
X865933Y-50111D01*
X867462Y-48361D01*
G01X894165D02*
X895912Y-49819D01*
X897877Y-50694D01*
X899623D01*
X901370Y-49819D01*
X902680Y-48361D01*
X903335Y-46319D01*
X902898Y-44278D01*
X901807Y-42527D01*
X899842Y-41361D01*
X897222Y-40777D01*
X895693Y-39611D01*
X895038Y-37569D01*
X895475Y-35527D01*
X896567Y-34069D01*
X898095Y-33194D01*
X899623D01*
X901152Y-33777D01*
X902462Y-35236D01*
G01X920617Y-50694D02*
X911883D01*
Y-33194D01*
X920617D01*
G01X917123Y-41652D02*
X911883D01*
G01X951250Y-39028D02*
Y-50694D01*
G01Y-34361D02*
X950813Y-34069D01*
Y-33486D01*
X951250Y-33194D01*
X951687Y-33486D01*
Y-34069D01*
X951250Y-34361D01*
G01X962200Y-50694D02*
Y-39028D01*
G01Y-42236D02*
X962855Y-40777D01*
X963947Y-39611D01*
X965475Y-39028D01*
X967003Y-39611D01*
X968095Y-40777D01*
X968750Y-42236D01*
Y-50694D01*
G01Y-42236D02*
X969405Y-40777D01*
X970496Y-39611D01*
X972025Y-39028D01*
X973553Y-39611D01*
X974645Y-40777D01*
X975300Y-42527D01*
Y-50694D01*
G01X982320Y-56527D02*
Y-39028D01*
G01Y-41652D02*
X983412Y-40194D01*
X984503Y-39319D01*
X986250Y-39028D01*
X987778Y-39319D01*
X989307Y-40777D01*
X989962Y-42819D01*
X990180Y-44861D01*
X989962Y-46903D01*
X989307Y-48944D01*
X987996Y-50111D01*
X986250Y-50694D01*
X984722Y-50402D01*
X983193Y-49528D01*
X982320Y-48361D01*
G01X1000475Y-42819D02*
X1007462D01*
X1006807Y-40777D01*
X1005715Y-39611D01*
X1004187Y-39028D01*
X1002658Y-39319D01*
X1001348Y-40194D01*
X1000475Y-42236D01*
X1000038Y-43986D01*
Y-45736D01*
X1000475Y-47486D01*
X1001567Y-49236D01*
X1002877Y-50402D01*
X1004405Y-50694D01*
X1005933Y-50111D01*
X1007462Y-48361D01*
G01X1025180Y-33194D02*
Y-50694D01*
G01Y-48070D02*
X1024307Y-49528D01*
X1022996Y-50402D01*
X1021468Y-50694D01*
X1019722Y-50111D01*
X1018412Y-48653D01*
X1017538Y-46903D01*
X1017320Y-44861D01*
X1017538Y-42819D01*
X1018412Y-41069D01*
X1019722Y-39611D01*
X1021468Y-39028D01*
X1022996Y-39319D01*
X1024088Y-39903D01*
X1025180Y-41069D01*
G01X1042680Y-50694D02*
Y-39028D01*
G01Y-41069D02*
X1041807Y-39903D01*
X1040496Y-39319D01*
X1038968Y-39028D01*
X1037440Y-39611D01*
X1036130Y-40777D01*
X1035256Y-42527D01*
X1034820Y-44861D01*
X1035256Y-47194D01*
X1036130Y-48944D01*
X1037440Y-50111D01*
X1038968Y-50694D01*
X1040496Y-50402D01*
X1041807Y-49528D01*
X1042680Y-48361D01*
G01X1052538Y-50694D02*
Y-39028D01*
G01Y-41944D02*
X1053412Y-40486D01*
X1054722Y-39319D01*
X1056468Y-39028D01*
X1057996Y-39319D01*
X1059307Y-40486D01*
X1059962Y-42527D01*
Y-50694D01*
G01X1077243Y-40486D02*
X1075715Y-39319D01*
X1074405Y-39028D01*
X1072658Y-39611D01*
X1071348Y-40777D01*
X1070475Y-42819D01*
X1070256Y-44861D01*
X1070475Y-46903D01*
X1071348Y-48653D01*
X1072658Y-50111D01*
X1074405Y-50694D01*
X1075933Y-50111D01*
X1077243Y-48944D01*
G01X1087975Y-42819D02*
X1094962D01*
X1094307Y-40777D01*
X1093215Y-39611D01*
X1091687Y-39028D01*
X1090158Y-39319D01*
X1088848Y-40194D01*
X1087975Y-42236D01*
X1087538Y-43986D01*
Y-45736D01*
X1087975Y-47486D01*
X1089067Y-49236D01*
X1090377Y-50402D01*
X1091905Y-50694D01*
X1093433Y-50111D01*
X1094962Y-48361D01*
G01X1126250Y-33194D02*
Y-50694D01*
G01X1123193Y-39028D02*
X1129307D01*
G01X1140693Y-50694D02*
Y-39028D01*
G01Y-41361D02*
X1141785Y-40194D01*
X1142877Y-39319D01*
X1144405Y-39028D01*
X1145496Y-39319D01*
X1146807Y-40194D01*
G01X1165180Y-50694D02*
Y-39028D01*
G01Y-41069D02*
X1164307Y-39903D01*
X1162996Y-39319D01*
X1161468Y-39028D01*
X1159940Y-39611D01*
X1158630Y-40777D01*
X1157756Y-42527D01*
X1157320Y-44861D01*
X1157756Y-47194D01*
X1158630Y-48944D01*
X1159940Y-50111D01*
X1161468Y-50694D01*
X1162996Y-50402D01*
X1164307Y-49528D01*
X1165180Y-48361D01*
G01X1182243Y-40486D02*
X1180715Y-39319D01*
X1179405Y-39028D01*
X1177658Y-39611D01*
X1176348Y-40777D01*
X1175475Y-42819D01*
X1175256Y-44861D01*
X1175475Y-46903D01*
X1176348Y-48653D01*
X1177658Y-50111D01*
X1179405Y-50694D01*
X1180933Y-50111D01*
X1182243Y-48944D01*
G01X1192975Y-42819D02*
X1199962D01*
X1199307Y-40777D01*
X1198215Y-39611D01*
X1196687Y-39028D01*
X1195158Y-39319D01*
X1193848Y-40194D01*
X1192975Y-42236D01*
X1192538Y-43986D01*
Y-45736D01*
X1192975Y-47486D01*
X1194067Y-49236D01*
X1195377Y-50402D01*
X1196905Y-50694D01*
X1198433Y-50111D01*
X1199962Y-48361D01*
G01X1210475Y-48653D02*
X1211567Y-49819D01*
X1213095Y-50694D01*
X1214405D01*
X1215715Y-50111D01*
X1216588Y-49236D01*
X1217025Y-48070D01*
X1216807Y-46319D01*
X1215933Y-45444D01*
X1212003Y-43694D01*
X1211130Y-41652D01*
X1211567Y-40194D01*
X1212440Y-39319D01*
X1213750Y-39028D01*
X1215060Y-39319D01*
X1216370Y-40194D01*
G01X1248750Y-39028D02*
Y-50694D01*
G01Y-34361D02*
X1248313Y-34069D01*
Y-33486D01*
X1248750Y-33194D01*
X1249187Y-33486D01*
Y-34069D01*
X1248750Y-34361D01*
G01X1262538Y-50694D02*
Y-39028D01*
G01Y-41944D02*
X1263412Y-40486D01*
X1264722Y-39319D01*
X1266468Y-39028D01*
X1267996Y-39319D01*
X1269307Y-40486D01*
X1269962Y-42527D01*
Y-50694D01*
G01X1301250D02*
Y-33194D01*
G01X1322680Y-50694D02*
Y-39028D01*
G01Y-41069D02*
X1321807Y-39903D01*
X1320496Y-39319D01*
X1318968Y-39028D01*
X1317440Y-39611D01*
X1316130Y-40777D01*
X1315256Y-42527D01*
X1314820Y-44861D01*
X1315256Y-47194D01*
X1316130Y-48944D01*
X1317440Y-50111D01*
X1318968Y-50694D01*
X1320496Y-50402D01*
X1321807Y-49528D01*
X1322680Y-48361D01*
G01X1331665Y-55944D02*
X1332975Y-56527D01*
X1334722Y-55944D01*
X1335813Y-54778D01*
X1336687Y-53319D01*
X1337996Y-48653D01*
X1340835Y-39028D01*
G01X1333848D02*
X1337996Y-48653D01*
G01X1350475Y-42819D02*
X1357462D01*
X1356807Y-40777D01*
X1355715Y-39611D01*
X1354187Y-39028D01*
X1352658Y-39319D01*
X1351348Y-40194D01*
X1350475Y-42236D01*
X1350038Y-43986D01*
Y-45736D01*
X1350475Y-47486D01*
X1351567Y-49236D01*
X1352877Y-50402D01*
X1354405Y-50694D01*
X1355933Y-50111D01*
X1357462Y-48361D01*
G01X1368193Y-50694D02*
Y-39028D01*
G01Y-41361D02*
X1369285Y-40194D01*
X1370377Y-39319D01*
X1371905Y-39028D01*
X1372996Y-39319D01*
X1374307Y-40194D01*
G01X1401883Y-33194D02*
Y-50694D01*
X1410617D01*
G01X1423750D02*
X1425278Y-50402D01*
X1427025Y-49528D01*
X1428117Y-48070D01*
X1428553Y-46027D01*
X1428117Y-43986D01*
X1426807Y-42236D01*
X1424842Y-41361D01*
X1422658D01*
X1421348Y-40777D01*
X1420256Y-39319D01*
X1419820Y-37278D01*
X1420475Y-35236D01*
X1422003Y-33777D01*
X1423750Y-33194D01*
X1425496Y-33777D01*
X1427025Y-35236D01*
X1427680Y-37278D01*
X1427243Y-39319D01*
X1426152Y-40777D01*
X1424842Y-41361D01*
X1422658D01*
X1420693Y-42236D01*
X1419383Y-43986D01*
X1418947Y-46027D01*
X1419383Y-48070D01*
X1420475Y-49528D01*
X1422222Y-50402D01*
X1423750Y-50694D01*
G01X1441250Y-51277D02*
X1440813Y-50986D01*
Y-50402D01*
X1441250Y-50111D01*
X1441687Y-50402D01*
Y-50986D01*
X1441250Y-51277D01*
G01X1987108Y1497418D02*
X1988855Y1495960D01*
X1990820Y1495085D01*
X1992566D01*
X1994313Y1495960D01*
X1995623Y1497418D01*
X1996278Y1499460D01*
X1995841Y1501501D01*
X1994750Y1503252D01*
X1992785Y1504418D01*
X1990165Y1505002D01*
X1988636Y1506168D01*
X1987981Y1508210D01*
X1988418Y1510252D01*
X1989510Y1511710D01*
X1991038Y1512585D01*
X1992566D01*
X1994095Y1512002D01*
X1995405Y1510543D01*
G01X2013560Y1495085D02*
X2004826D01*
Y1512585D01*
X2013560D01*
G01X2010066Y1504127D02*
X2004826D01*
G01X2041573Y1512585D02*
X2046813D01*
G01X2044193D02*
Y1495085D01*
G01X2041573D02*
X2046813D01*
G01X2056016D02*
Y1512585D01*
X2061693Y1498002D01*
X2067370Y1512585D01*
Y1495085D01*
G01X2074826D02*
Y1512585D01*
X2080066D01*
X2081813Y1511710D01*
X2083123Y1509668D01*
X2083560Y1507335D01*
X2083123Y1505002D01*
X2082031Y1503252D01*
X2080066Y1502376D01*
X2074826D01*
G01X2101060Y1495085D02*
X2092326D01*
Y1512585D01*
X2101060D01*
G01X2097566Y1504127D02*
X2092326D01*
G01X2109390Y1495085D02*
Y1512585D01*
X2113756D01*
X2115503Y1511710D01*
X2116813Y1510543D01*
X2117905Y1508794D01*
X2118778Y1506751D01*
X2118996Y1503835D01*
X2118778Y1500918D01*
X2117905Y1498876D01*
X2116813Y1497126D01*
X2115503Y1495960D01*
X2113756Y1495085D01*
X2109390D01*
G01X2126234D02*
X2131693Y1512585D01*
X2137152Y1495085D01*
G01X2135186Y1501210D02*
X2128199D01*
G01X2144171Y1495085D02*
Y1512585D01*
X2154215Y1495085D01*
Y1512585D01*
G01X2171496Y1511126D02*
X2170186Y1512002D01*
X2168658Y1512585D01*
X2166911D01*
X2164946Y1511710D01*
X2163418Y1510252D01*
X2162326Y1508501D01*
X2161453Y1505585D01*
X2161234Y1502960D01*
X2161671Y1500335D01*
X2162326Y1498585D01*
X2163636Y1496835D01*
X2165165Y1495668D01*
X2166693Y1495085D01*
X2168221D01*
X2169750Y1495668D01*
X2171060Y1496543D01*
X2172152Y1497709D01*
G01X2188560Y1495085D02*
X2179826D01*
Y1512585D01*
X2188560D01*
G01X2185066Y1504127D02*
X2179826D01*
G01X2219193Y1512585D02*
Y1495085D01*
G01X2214171Y1512585D02*
X2224215D01*
G01X2231234Y1495085D02*
X2236693Y1512585D01*
X2242152Y1495085D01*
G01X2240186Y1501210D02*
X2233199D01*
G01X2255939Y1504418D02*
X2256813Y1505293D01*
X2257468Y1506751D01*
X2257905Y1508794D01*
X2257468Y1510543D01*
X2256595Y1511710D01*
X2255066Y1512585D01*
X2249171D01*
Y1495085D01*
X2256376D01*
X2257905Y1496251D01*
X2258778Y1498002D01*
X2259215Y1500043D01*
X2258778Y1502085D01*
X2257468Y1503835D01*
X2255939Y1504418D01*
X2249171D01*
G01X2267326Y1512585D02*
Y1495085D01*
X2276060D01*
G01X2293560D02*
X2284826D01*
Y1512585D01*
X2293560D01*
G01X2290066Y1504127D02*
X2284826D01*
G01X2306693Y1494502D02*
X2306256Y1494793D01*
Y1495377D01*
X2306693Y1495668D01*
X2307130Y1495377D01*
Y1494793D01*
X2306693Y1494502D01*
G01Y1502376D02*
X2306256Y1502668D01*
Y1503252D01*
X2306693Y1503543D01*
X2307130Y1503252D01*
Y1502668D01*
X2306693Y1502376D01*
G01X2337326Y1512585D02*
Y1495085D01*
X2346060D01*
G01X2359193D02*
X2360721Y1495377D01*
X2362468Y1496251D01*
X2363560Y1497709D01*
X2363996Y1499752D01*
X2363560Y1501793D01*
X2362250Y1503543D01*
X2360285Y1504418D01*
X2358101D01*
X2356791Y1505002D01*
X2355699Y1506460D01*
X2355263Y1508501D01*
X2355918Y1510543D01*
X2357446Y1512002D01*
X2359193Y1512585D01*
X2360939Y1512002D01*
X2362468Y1510543D01*
X2363123Y1508501D01*
X2362686Y1506460D01*
X2361595Y1505002D01*
X2360285Y1504418D01*
X2358101D01*
X2356136Y1503543D01*
X2354826Y1501793D01*
X2354390Y1499752D01*
X2354826Y1497709D01*
X2355918Y1496251D01*
X2357665Y1495377D01*
X2359193Y1495085D01*
G01X2008773Y1477935D02*
X2014013D01*
G01X2011393D02*
Y1460435D01*
G01X2008773D02*
X2014013D01*
G01X2023216D02*
Y1477935D01*
X2028893Y1463352D01*
X2034570Y1477935D01*
Y1460435D01*
G01X2042026D02*
Y1477935D01*
X2047266D01*
X2049013Y1477060D01*
X2050323Y1475018D01*
X2050760Y1472685D01*
X2050323Y1470352D01*
X2049231Y1468602D01*
X2047266Y1467726D01*
X2042026D01*
G01X2062801Y1454602D02*
X2060618Y1457518D01*
X2059526Y1460435D01*
Y1472101D01*
X2060618Y1475018D01*
X2062801Y1477935D01*
G01X2081393Y1460435D02*
X2079646Y1460727D01*
X2078118Y1461893D01*
X2076808Y1463643D01*
X2075934Y1465685D01*
X2075498Y1468018D01*
Y1470352D01*
X2075934Y1472685D01*
X2076808Y1474727D01*
X2078118Y1476476D01*
X2079646Y1477643D01*
X2081393Y1477935D01*
X2083139Y1477643D01*
X2084668Y1476476D01*
X2085978Y1474727D01*
X2086852Y1472685D01*
X2087288Y1470352D01*
Y1468018D01*
X2086852Y1465685D01*
X2085978Y1463643D01*
X2084668Y1461893D01*
X2083139Y1460727D01*
X2081393Y1460435D01*
G01X2095181D02*
Y1477935D01*
G01Y1469477D02*
X2096273Y1470935D01*
X2097365Y1471810D01*
X2099111Y1472101D01*
X2100421Y1471810D01*
X2101950Y1470643D01*
X2102605Y1468893D01*
Y1460435D01*
G01X2109843D02*
Y1472101D01*
G01Y1468893D02*
X2110498Y1470352D01*
X2111590Y1471518D01*
X2113118Y1472101D01*
X2114646Y1471518D01*
X2115738Y1470352D01*
X2116393Y1468893D01*
Y1460435D01*
G01Y1468893D02*
X2117048Y1470352D01*
X2118139Y1471518D01*
X2119668Y1472101D01*
X2121196Y1471518D01*
X2122288Y1470352D01*
X2122943Y1468602D01*
Y1460435D01*
G01X2134985Y1454602D02*
X2137168Y1457518D01*
X2138260Y1460435D01*
Y1472101D01*
X2137168Y1475018D01*
X2134985Y1477935D01*
G01X2041590Y1428409D02*
X2042899Y1426951D01*
X2044428Y1426077D01*
X2046393Y1425785D01*
X2048358Y1426368D01*
X2049886Y1427535D01*
X2050978Y1429576D01*
X2051196Y1431910D01*
X2050760Y1434243D01*
X2049668Y1435702D01*
X2048139Y1436868D01*
X2046611Y1437160D01*
X2045083Y1436868D01*
X2043118Y1435702D01*
X2043773Y1443285D01*
X2049668D01*
G01X2063893D02*
X2062146Y1442702D01*
X2060836Y1441243D01*
X2059963Y1439494D01*
X2059308Y1437160D01*
X2059090Y1434535D01*
X2059308Y1431910D01*
X2059963Y1429576D01*
X2060836Y1427826D01*
X2062146Y1426368D01*
X2063893Y1425785D01*
X2065639Y1426368D01*
X2066950Y1427826D01*
X2067823Y1429576D01*
X2068478Y1431910D01*
X2068696Y1434535D01*
X2068478Y1437160D01*
X2067823Y1439494D01*
X2066950Y1441243D01*
X2065639Y1442702D01*
X2063893Y1443285D01*
G01X2081393Y1425202D02*
X2080956Y1425493D01*
Y1426077D01*
X2081393Y1426368D01*
X2081830Y1426077D01*
Y1425493D01*
X2081393Y1425202D01*
G01X2098893Y1443285D02*
X2097146Y1442702D01*
X2095836Y1441243D01*
X2094963Y1439494D01*
X2094308Y1437160D01*
X2094090Y1434535D01*
X2094308Y1431910D01*
X2094963Y1429576D01*
X2095836Y1427826D01*
X2097146Y1426368D01*
X2098893Y1425785D01*
X2100639Y1426368D01*
X2101950Y1427826D01*
X2102823Y1429576D01*
X2103478Y1431910D01*
X2103696Y1434535D01*
X2103478Y1437160D01*
X2102823Y1439494D01*
X2101950Y1441243D01*
X2100639Y1442702D01*
X2098893Y1443285D01*
G01X2179843Y1477935D02*
X2182899Y1460435D01*
X2186393Y1477935D01*
X2189886Y1460435D01*
X2192943Y1477935D01*
G01X2201273D02*
X2206513D01*
G01X2203893D02*
Y1460435D01*
G01X2201273D02*
X2206513D01*
G01X2216590D02*
Y1477935D01*
X2220956D01*
X2222703Y1477060D01*
X2224013Y1475893D01*
X2225105Y1474144D01*
X2225978Y1472101D01*
X2226196Y1469185D01*
X2225978Y1466268D01*
X2225105Y1464226D01*
X2224013Y1462476D01*
X2222703Y1461310D01*
X2220956Y1460435D01*
X2216590D01*
G01X2238893Y1477935D02*
Y1460435D01*
G01X2233871Y1477935D02*
X2243915D01*
G01X2251808Y1460435D02*
Y1477935D01*
G01X2260978D02*
Y1460435D01*
G01Y1469185D02*
X2251808D01*
G01X2272801Y1454602D02*
X2270618Y1457518D01*
X2269526Y1460435D01*
Y1472101D01*
X2270618Y1475018D01*
X2272801Y1477935D01*
G01X2284843Y1460435D02*
Y1472101D01*
G01Y1468893D02*
X2285498Y1470352D01*
X2286590Y1471518D01*
X2288118Y1472101D01*
X2289646Y1471518D01*
X2290738Y1470352D01*
X2291393Y1468893D01*
Y1460435D01*
G01Y1468893D02*
X2292048Y1470352D01*
X2293139Y1471518D01*
X2294668Y1472101D01*
X2296196Y1471518D01*
X2297288Y1470352D01*
X2297943Y1468602D01*
Y1460435D01*
G01X2308893Y1472101D02*
Y1460435D01*
G01Y1476768D02*
X2308456Y1477060D01*
Y1477643D01*
X2308893Y1477935D01*
X2309330Y1477643D01*
Y1477060D01*
X2308893Y1476768D01*
G01X2326393Y1460435D02*
Y1477935D01*
G01X2340618Y1462476D02*
X2341710Y1461310D01*
X2343238Y1460435D01*
X2344548D01*
X2345858Y1461018D01*
X2346731Y1461893D01*
X2347168Y1463059D01*
X2346950Y1464810D01*
X2346076Y1465685D01*
X2342146Y1467435D01*
X2341273Y1469477D01*
X2341710Y1470935D01*
X2342583Y1471810D01*
X2343893Y1472101D01*
X2345203Y1471810D01*
X2346513Y1470935D01*
G01X2362485Y1454602D02*
X2364668Y1457518D01*
X2365760Y1460435D01*
Y1472101D01*
X2364668Y1475018D01*
X2362485Y1477935D01*
G01X2243495Y1433076D02*
X2245023Y1435118D01*
X2246333Y1436285D01*
X2248080Y1436868D01*
X2249608Y1436285D01*
X2250700Y1435118D01*
X2251573Y1433368D01*
X2251791Y1431327D01*
X2251573Y1429576D01*
X2250700Y1427826D01*
X2249389Y1426368D01*
X2247861Y1425785D01*
X2246115Y1426368D01*
X2244586Y1428118D01*
X2243713Y1430743D01*
X2243495Y1433660D01*
X2243931Y1437451D01*
X2244586Y1439494D01*
X2245678Y1441535D01*
X2247206Y1442993D01*
X2248735Y1443285D01*
X2250263Y1442702D01*
X2251355Y1441243D01*
G01X2265143Y1425202D02*
X2264706Y1425493D01*
Y1426077D01*
X2265143Y1426368D01*
X2265580Y1426077D01*
Y1425493D01*
X2265143Y1425202D01*
G01X2282206Y1425785D02*
X2282643Y1429576D01*
X2283298Y1432785D01*
X2284171Y1435702D01*
X2285263Y1438910D01*
X2287010Y1443285D01*
X2278276D01*
G01X2295340Y1428409D02*
X2296649Y1426951D01*
X2298178Y1426077D01*
X2300143Y1425785D01*
X2302108Y1426368D01*
X2303636Y1427535D01*
X2304728Y1429576D01*
X2304946Y1431910D01*
X2304510Y1434243D01*
X2303418Y1435702D01*
X2301889Y1436868D01*
X2300361Y1437160D01*
X2298833Y1436868D01*
X2296868Y1435702D01*
X2297523Y1443285D01*
X2303418D01*
G01X2426808Y1428118D02*
X2428555Y1426660D01*
X2430520Y1425785D01*
X2432266D01*
X2434013Y1426660D01*
X2435323Y1428118D01*
X2435978Y1430160D01*
X2435541Y1432201D01*
X2434450Y1433952D01*
X2432485Y1435118D01*
X2429865Y1435702D01*
X2428336Y1436868D01*
X2427681Y1438910D01*
X2428118Y1440952D01*
X2429210Y1442410D01*
X2430738Y1443285D01*
X2432266D01*
X2433795Y1442702D01*
X2435105Y1441243D01*
G01X2453260Y1425785D02*
X2444526D01*
Y1443285D01*
X2453260D01*
G01X2449766Y1434827D02*
X2444526D01*
G01X2413893Y1477935D02*
Y1460435D01*
G01X2408871Y1477935D02*
X2418915D01*
G01X2431393Y1460435D02*
Y1468310D01*
X2427026Y1477935D01*
G01X2435760D02*
X2431393Y1468310D01*
G01X2444526Y1460435D02*
Y1477935D01*
X2449766D01*
X2451513Y1477060D01*
X2452823Y1475018D01*
X2453260Y1472685D01*
X2452823Y1470352D01*
X2451731Y1468602D01*
X2449766Y1467726D01*
X2444526D01*
G01X2470760Y1460435D02*
X2462026D01*
Y1477935D01*
X2470760D01*
G01X2467266Y1469477D02*
X2462026D01*
G01X2514526Y1460435D02*
Y1477935D01*
X2519985D01*
X2521731Y1477060D01*
X2522823Y1475893D01*
X2523260Y1473560D01*
X2522823Y1471226D01*
X2521513Y1469768D01*
X2519985Y1468893D01*
X2514526D01*
G01X2519985D02*
X2523260Y1460435D01*
G01X2533118Y1468310D02*
X2540105D01*
X2539450Y1470352D01*
X2538358Y1471518D01*
X2536830Y1472101D01*
X2535301Y1471810D01*
X2533991Y1470935D01*
X2533118Y1468893D01*
X2532681Y1467143D01*
Y1465393D01*
X2533118Y1463643D01*
X2534210Y1461893D01*
X2535520Y1460727D01*
X2537048Y1460435D01*
X2538576Y1461018D01*
X2540105Y1462768D01*
G01X2552583Y1460435D02*
Y1475310D01*
X2553020Y1476768D01*
X2553893Y1477643D01*
X2555203Y1477935D01*
X2556513Y1477352D01*
X2557168Y1475893D01*
G01X2554548Y1470935D02*
X2550181D01*
G01X2571393Y1459852D02*
X2570956Y1460143D01*
Y1460727D01*
X2571393Y1461018D01*
X2571830Y1460727D01*
Y1460143D01*
X2571393Y1459852D01*
G01X2602026Y1460435D02*
Y1477935D01*
X2607266D01*
X2609013Y1477060D01*
X2610323Y1475018D01*
X2610760Y1472685D01*
X2610323Y1470352D01*
X2609231Y1468602D01*
X2607266Y1467726D01*
X2602026D01*
G01X2623893Y1460435D02*
Y1477935D01*
G01X2645323Y1460435D02*
Y1472101D01*
G01Y1470060D02*
X2644450Y1471226D01*
X2643139Y1471810D01*
X2641611Y1472101D01*
X2640083Y1471518D01*
X2638773Y1470352D01*
X2637899Y1468602D01*
X2637463Y1466268D01*
X2637899Y1463935D01*
X2638773Y1462185D01*
X2640083Y1461018D01*
X2641611Y1460435D01*
X2643139Y1460727D01*
X2644450Y1461601D01*
X2645323Y1462768D01*
G01X2655181Y1460435D02*
Y1472101D01*
G01Y1469185D02*
X2656055Y1470643D01*
X2657365Y1471810D01*
X2659111Y1472101D01*
X2660639Y1471810D01*
X2661950Y1470643D01*
X2662605Y1468602D01*
Y1460435D01*
G01X2673118Y1468310D02*
X2680105D01*
X2679450Y1470352D01*
X2678358Y1471518D01*
X2676830Y1472101D01*
X2675301Y1471810D01*
X2673991Y1470935D01*
X2673118Y1468893D01*
X2672681Y1467143D01*
Y1465393D01*
X2673118Y1463643D01*
X2674210Y1461893D01*
X2675520Y1460727D01*
X2677048Y1460435D01*
X2678576Y1461018D01*
X2680105Y1462768D01*
G01X2584526Y1443285D02*
Y1425785D01*
X2593260D01*
G01X2605956D02*
X2606393Y1429576D01*
X2607048Y1432785D01*
X2607921Y1435702D01*
X2609013Y1438910D01*
X2610760Y1443285D01*
X2602026D01*
G01X2794193Y1437451D02*
Y1425785D01*
G01Y1442118D02*
X2793756Y1442410D01*
Y1442993D01*
X2794193Y1443285D01*
X2794630Y1442993D01*
Y1442410D01*
X2794193Y1442118D01*
G01X2808418Y1427826D02*
X2809510Y1426660D01*
X2811038Y1425785D01*
X2812348D01*
X2813658Y1426368D01*
X2814531Y1427243D01*
X2814968Y1428409D01*
X2814750Y1430160D01*
X2813876Y1431035D01*
X2809946Y1432785D01*
X2809073Y1434827D01*
X2809510Y1436285D01*
X2810383Y1437160D01*
X2811693Y1437451D01*
X2813003Y1437160D01*
X2814313Y1436285D01*
G01X2841671Y1425785D02*
Y1443285D01*
X2851715Y1425785D01*
Y1443285D01*
G01X2864193Y1425785D02*
X2862446Y1426077D01*
X2860918Y1427243D01*
X2859608Y1428993D01*
X2858734Y1431035D01*
X2858298Y1433368D01*
Y1435702D01*
X2858734Y1438035D01*
X2859608Y1440077D01*
X2860918Y1441826D01*
X2862446Y1442993D01*
X2864193Y1443285D01*
X2865939Y1442993D01*
X2867468Y1441826D01*
X2868778Y1440077D01*
X2869652Y1438035D01*
X2870088Y1435702D01*
Y1433368D01*
X2869652Y1431035D01*
X2868778Y1428993D01*
X2867468Y1427243D01*
X2865939Y1426077D01*
X2864193Y1425785D01*
G01X2881693Y1443285D02*
Y1425785D01*
G01X2876671Y1443285D02*
X2886715D01*
G01X2912981Y1437451D02*
Y1429285D01*
X2913855Y1427243D01*
X2915165Y1426077D01*
X2916693Y1425785D01*
X2918221Y1426077D01*
X2919531Y1427243D01*
X2920405Y1429285D01*
G01Y1425785D02*
Y1437451D01*
G01X2930918Y1427826D02*
X2932010Y1426660D01*
X2933538Y1425785D01*
X2934848D01*
X2936158Y1426368D01*
X2937031Y1427243D01*
X2937468Y1428409D01*
X2937250Y1430160D01*
X2936376Y1431035D01*
X2932446Y1432785D01*
X2931573Y1434827D01*
X2932010Y1436285D01*
X2932883Y1437160D01*
X2934193Y1437451D01*
X2935503Y1437160D01*
X2936813Y1436285D01*
G01X2948418Y1433660D02*
X2955405D01*
X2954750Y1435702D01*
X2953658Y1436868D01*
X2952130Y1437451D01*
X2950601Y1437160D01*
X2949291Y1436285D01*
X2948418Y1434243D01*
X2947981Y1432493D01*
Y1430743D01*
X2948418Y1428993D01*
X2949510Y1427243D01*
X2950820Y1426077D01*
X2952348Y1425785D01*
X2953876Y1426368D01*
X2955405Y1428118D01*
G01X2973123Y1443285D02*
Y1425785D01*
G01Y1428409D02*
X2972250Y1426951D01*
X2970939Y1426077D01*
X2969411Y1425785D01*
X2967665Y1426368D01*
X2966355Y1427826D01*
X2965481Y1429576D01*
X2965263Y1431618D01*
X2965481Y1433660D01*
X2966355Y1435410D01*
X2967665Y1436868D01*
X2969411Y1437451D01*
X2970939Y1437160D01*
X2972031Y1436576D01*
X2973123Y1435410D01*
G01X2719390Y1459852D02*
X2728996Y1472685D01*
G01X2724193Y1475018D02*
Y1457518D01*
G01X2728996Y1459852D02*
X2719390Y1472685D01*
G01X2717643Y1466268D02*
X2730743D01*
G01X2756355D02*
X2762031D01*
G01X2789390Y1460435D02*
Y1477935D01*
X2793756D01*
X2795503Y1477060D01*
X2796813Y1475893D01*
X2797905Y1474144D01*
X2798778Y1472101D01*
X2798996Y1469185D01*
X2798778Y1466268D01*
X2797905Y1464226D01*
X2796813Y1462476D01*
X2795503Y1461310D01*
X2793756Y1460435D01*
X2789390D01*
G01X2808418Y1468310D02*
X2815405D01*
X2814750Y1470352D01*
X2813658Y1471518D01*
X2812130Y1472101D01*
X2810601Y1471810D01*
X2809291Y1470935D01*
X2808418Y1468893D01*
X2807981Y1467143D01*
Y1465393D01*
X2808418Y1463643D01*
X2809510Y1461893D01*
X2810820Y1460727D01*
X2812348Y1460435D01*
X2813876Y1461018D01*
X2815405Y1462768D01*
G01X2825481Y1460435D02*
Y1472101D01*
G01Y1469185D02*
X2826355Y1470643D01*
X2827665Y1471810D01*
X2829411Y1472101D01*
X2830939Y1471810D01*
X2832250Y1470643D01*
X2832905Y1468602D01*
Y1460435D01*
G01X2846693D02*
X2845383Y1460727D01*
X2844073Y1461893D01*
X2843199Y1463935D01*
X2842763Y1466268D01*
X2843199Y1468602D01*
X2844073Y1470643D01*
X2845383Y1471810D01*
X2846693Y1472101D01*
X2848003Y1471810D01*
X2849313Y1470643D01*
X2850186Y1468602D01*
X2850405Y1466268D01*
X2850186Y1463935D01*
X2849313Y1461893D01*
X2848003Y1460727D01*
X2846693Y1460435D01*
G01X2864193Y1477935D02*
Y1460435D01*
G01X2861136Y1472101D02*
X2867250D01*
G01X2878418Y1468310D02*
X2885405D01*
X2884750Y1470352D01*
X2883658Y1471518D01*
X2882130Y1472101D01*
X2880601Y1471810D01*
X2879291Y1470935D01*
X2878418Y1468893D01*
X2877981Y1467143D01*
Y1465393D01*
X2878418Y1463643D01*
X2879510Y1461893D01*
X2880820Y1460727D01*
X2882348Y1460435D01*
X2883876Y1461018D01*
X2885405Y1462768D01*
G01X2895918Y1462476D02*
X2897010Y1461310D01*
X2898538Y1460435D01*
X2899848D01*
X2901158Y1461018D01*
X2902031Y1461893D01*
X2902468Y1463059D01*
X2902250Y1464810D01*
X2901376Y1465685D01*
X2897446Y1467435D01*
X2896573Y1469477D01*
X2897010Y1470935D01*
X2897883Y1471810D01*
X2899193Y1472101D01*
X2900503Y1471810D01*
X2901813Y1470935D01*
G01X2934193Y1477935D02*
Y1460435D01*
G01X2931136Y1472101D02*
X2937250D01*
G01X2947981Y1460435D02*
Y1477935D01*
G01Y1469477D02*
X2949073Y1470935D01*
X2950165Y1471810D01*
X2951911Y1472101D01*
X2953221Y1471810D01*
X2954750Y1470643D01*
X2955405Y1468893D01*
Y1460435D01*
G01X2973123D02*
Y1472101D01*
G01Y1470060D02*
X2972250Y1471226D01*
X2970939Y1471810D01*
X2969411Y1472101D01*
X2967883Y1471518D01*
X2966573Y1470352D01*
X2965699Y1468602D01*
X2965263Y1466268D01*
X2965699Y1463935D01*
X2966573Y1462185D01*
X2967883Y1461018D01*
X2969411Y1460435D01*
X2970939Y1460727D01*
X2972250Y1461601D01*
X2973123Y1462768D01*
G01X2986693Y1477935D02*
Y1460435D01*
G01X2983636Y1472101D02*
X2989750D01*
G01X3021693Y1477935D02*
Y1460435D01*
G01X3018636Y1472101D02*
X3024750D01*
G01X3035481Y1460435D02*
Y1477935D01*
G01Y1469477D02*
X3036573Y1470935D01*
X3037665Y1471810D01*
X3039411Y1472101D01*
X3040721Y1471810D01*
X3042250Y1470643D01*
X3042905Y1468893D01*
Y1460435D01*
G01X3056693Y1472101D02*
Y1460435D01*
G01Y1476768D02*
X3056256Y1477060D01*
Y1477643D01*
X3056693Y1477935D01*
X3057130Y1477643D01*
Y1477060D01*
X3056693Y1476768D01*
G01X3070918Y1462476D02*
X3072010Y1461310D01*
X3073538Y1460435D01*
X3074848D01*
X3076158Y1461018D01*
X3077031Y1461893D01*
X3077468Y1463059D01*
X3077250Y1464810D01*
X3076376Y1465685D01*
X3072446Y1467435D01*
X3071573Y1469477D01*
X3072010Y1470935D01*
X3072883Y1471810D01*
X3074193Y1472101D01*
X3075503Y1471810D01*
X3076813Y1470935D01*
G01X3106573Y1477935D02*
X3111813D01*
G01X3109193D02*
Y1460435D01*
G01X3106573D02*
X3111813D01*
G01X3120143D02*
Y1472101D01*
G01Y1468893D02*
X3120798Y1470352D01*
X3121890Y1471518D01*
X3123418Y1472101D01*
X3124946Y1471518D01*
X3126038Y1470352D01*
X3126693Y1468893D01*
Y1460435D01*
G01Y1468893D02*
X3127348Y1470352D01*
X3128439Y1471518D01*
X3129968Y1472101D01*
X3131496Y1471518D01*
X3132588Y1470352D01*
X3133243Y1468602D01*
Y1460435D01*
G01X3140263Y1454602D02*
Y1472101D01*
G01Y1469477D02*
X3141355Y1470935D01*
X3142446Y1471810D01*
X3144193Y1472101D01*
X3145721Y1471810D01*
X3147250Y1470352D01*
X3147905Y1468310D01*
X3148123Y1466268D01*
X3147905Y1464226D01*
X3147250Y1462185D01*
X3145939Y1461018D01*
X3144193Y1460435D01*
X3142665Y1460727D01*
X3141136Y1461601D01*
X3140263Y1462768D01*
G01X3158418Y1468310D02*
X3165405D01*
X3164750Y1470352D01*
X3163658Y1471518D01*
X3162130Y1472101D01*
X3160601Y1471810D01*
X3159291Y1470935D01*
X3158418Y1468893D01*
X3157981Y1467143D01*
Y1465393D01*
X3158418Y1463643D01*
X3159510Y1461893D01*
X3160820Y1460727D01*
X3162348Y1460435D01*
X3163876Y1461018D01*
X3165405Y1462768D01*
G01X3183123Y1477935D02*
Y1460435D01*
G01Y1463059D02*
X3182250Y1461601D01*
X3180939Y1460727D01*
X3179411Y1460435D01*
X3177665Y1461018D01*
X3176355Y1462476D01*
X3175481Y1464226D01*
X3175263Y1466268D01*
X3175481Y1468310D01*
X3176355Y1470060D01*
X3177665Y1471518D01*
X3179411Y1472101D01*
X3180939Y1471810D01*
X3182031Y1471226D01*
X3183123Y1470060D01*
G01X3200623Y1460435D02*
Y1472101D01*
G01Y1470060D02*
X3199750Y1471226D01*
X3198439Y1471810D01*
X3196911Y1472101D01*
X3195383Y1471518D01*
X3194073Y1470352D01*
X3193199Y1468602D01*
X3192763Y1466268D01*
X3193199Y1463935D01*
X3194073Y1462185D01*
X3195383Y1461018D01*
X3196911Y1460435D01*
X3198439Y1460727D01*
X3199750Y1461601D01*
X3200623Y1462768D01*
G01X3210481Y1460435D02*
Y1472101D01*
G01Y1469185D02*
X3211355Y1470643D01*
X3212665Y1471810D01*
X3214411Y1472101D01*
X3215939Y1471810D01*
X3217250Y1470643D01*
X3217905Y1468602D01*
Y1460435D01*
G01X3235186Y1470643D02*
X3233658Y1471810D01*
X3232348Y1472101D01*
X3230601Y1471518D01*
X3229291Y1470352D01*
X3228418Y1468310D01*
X3228199Y1466268D01*
X3228418Y1464226D01*
X3229291Y1462476D01*
X3230601Y1461018D01*
X3232348Y1460435D01*
X3233876Y1461018D01*
X3235186Y1462185D01*
G01X3245918Y1468310D02*
X3252905D01*
X3252250Y1470352D01*
X3251158Y1471518D01*
X3249630Y1472101D01*
X3248101Y1471810D01*
X3246791Y1470935D01*
X3245918Y1468893D01*
X3245481Y1467143D01*
Y1465393D01*
X3245918Y1463643D01*
X3247010Y1461893D01*
X3248320Y1460727D01*
X3249848Y1460435D01*
X3251376Y1461018D01*
X3252905Y1462768D01*
G01X0Y3937D02*
G03X3937Y0I3937J0D01*
G01X0Y3937D02*
G03X3937Y0I3937J0D01*
G01D02*
X779528D01*
G01X3937D02*
X779528D01*
G01X0Y1456693D02*
Y3937D01*
G01Y1456693D02*
Y3937D01*
G01X7874Y1460630D02*
X3937D01*
G01D02*
X7874D01*
G01X3937D02*
G03X0Y1456693I0J-3937D01*
G01X3937Y1460630D02*
G03X0Y1456693I0J-3937D01*
G01X101378Y1519685D02*
G03X97441Y1515748I0J-3937D01*
G01X101378Y1519685D02*
G03X97441Y1515748I0J-3937D01*
G01D02*
Y1509055D01*
G01Y1515748D02*
Y1509055D01*
G01X93504Y1505118D02*
X67913D01*
G01X93504D02*
G03X97441Y1509055I0J3937D01*
G01X93504Y1505118D02*
G03X97441Y1509055I0J3937D01*
G01X67913Y1505118D02*
X93504D01*
G01X63976Y1515748D02*
G03X60039Y1519685I-3937J0D01*
G01X63976Y1515748D02*
G03X60039Y1519685I-3937J0D01*
G01X63976Y1509055D02*
Y1515748D01*
G01Y1509055D02*
G03X67913Y1505118I3937J0D01*
G01X63976Y1509055D02*
G03X67913Y1505118I3937J0D01*
G01X63976Y1515748D02*
Y1509055D01*
G01X7874Y1460630D02*
G03X11811Y1464567I0J3937D01*
G01X7874Y1460630D02*
G03X11811Y1464567I0J3937D01*
G01X15748Y1519685D02*
G03X11811Y1515748I0J-3937D01*
G01X15748Y1519685D02*
G03X11811Y1515748I0J-3937D01*
G01D02*
Y1464567D01*
G01Y1515748D02*
Y1464567D01*
G01X60039Y1519685D02*
X15748D01*
G01X60039D02*
X15748D01*
G01X141181Y277843D02*
G03X148106Y264712I37662J11471D01*
G01X141181Y277843D02*
G03X148106Y264712I37662J11471D01*
G01X141181Y277843D02*
G03X121220I-9980J-3040D01*
G01X114295Y264712D02*
G03X121220Y277843I-30737J24602D01*
G01X141181D02*
G03X121220I-9980J-3040D01*
G01X114295Y264712D02*
G03X121220Y277843I-30737J24601D01*
G01X114295Y264712D02*
G03X148106I16905J-13531D01*
G01X114295D02*
G03X148106I16905J-13531D01*
G01X141181Y730599D02*
G03X148106Y717468I37662J11471D01*
G01X141181Y730599D02*
G03X148106Y717468I37662J11471D01*
G01X141181Y730599D02*
G03X121220I-9980J-3040D01*
G01X114295Y717468D02*
G03X121220Y730599I-30737J24601D01*
G01X141181D02*
G03X121220I-9980J-3040D01*
G01X114295Y717468D02*
G03X121220Y730599I-30737J24601D01*
G01X114295Y717468D02*
G03X148106I16905J-13531D01*
G01X114295D02*
G03X148106I16905J-13531D01*
G01X114295Y1170224D02*
G03X148106I16905J-13531D01*
G01X114295D02*
G03X148106I16905J-13531D01*
G01X141181Y1183355D02*
G03X148106Y1170224I37662J11471D01*
G01X141181Y1183355D02*
G03X148106Y1170224I37662J11471D01*
G01X141181Y1183355D02*
G03X121220I-9980J-3040D01*
G01X141181D02*
G03X121220I-9980J-3040D01*
G01X114295Y1170224D02*
G03X121220Y1183355I-30737J24602D01*
G01X114295Y1170224D02*
G03X121220Y1183355I-30737J24601D01*
G01X280709Y1519685D02*
X101378D01*
G01X280709D02*
X101378D01*
G01X284646Y1515748D02*
G03X280709Y1519685I-3937J0D01*
G01X284646Y1515748D02*
G03X280709Y1519685I-3937J0D01*
G01X284646Y1500000D02*
Y1515748D01*
G01Y1500000D02*
G03X288583Y1496063I3937J0D01*
G01X493307D02*
X288583D01*
G01X284646Y1500000D02*
G03X288583Y1496063I3937J0D01*
G01X493307D02*
X288583D01*
G01X284646Y1515748D02*
Y1500000D01*
G01X389213Y277843D02*
G03X369252I-9981J-3040D01*
G01X389213D02*
G03X369252I-9981J-3040D01*
G01X362327Y264712D02*
G03X369252Y277843I-30737J24602D01*
G01X362327Y264712D02*
G03X369252Y277843I-30737J24602D01*
G01X362327Y264712D02*
G03X396138I16905J-13531D01*
G01X362327D02*
G03X396138I16905J-13531D01*
G01X389213Y730599D02*
G03X369252I-9981J-3040D01*
G01X389213D02*
G03X369252I-9981J-3040D01*
G01X362327Y717468D02*
G03X369252Y730599I-30737J24602D01*
G01X362327Y717468D02*
G03X369252Y730599I-30737J24602D01*
G01X362327Y717468D02*
G03X396138I16905J-13531D01*
G01X362327D02*
G03X396138I16905J-13531D01*
G01X362327Y1170224D02*
G03X396138I16905J-13531D01*
G01X362327D02*
G03X396138I16905J-13531D01*
G01X389213Y1183355D02*
G03X369252I-9981J-3040D01*
G01X389213D02*
G03X369252I-9981J-3040D01*
G01X362327Y1170224D02*
G03X369252Y1183355I-30737J24602D01*
G01X362327Y1170224D02*
G03X369252Y1183355I-30737J24602D01*
G01X322441Y1503937D02*
G03Y1496063I0J-3937D01*
G01X459449Y1503937D02*
X322441D01*
G01X459449D02*
X322441D01*
G01D02*
G03Y1496063I0J-3937D01*
G01X296457Y1519685D02*
G03X292520Y1515748I0J-3937D01*
G01X296457Y1519685D02*
X485433D01*
G01X296457D02*
G03X292520Y1515748I0J-3937D01*
G01X296457Y1519685D02*
X485433D01*
G01X304331Y1503937D02*
X292520D01*
G01Y1515748D02*
Y1503937D01*
G01X304331D02*
X292520D01*
G01Y1515748D02*
Y1503937D01*
G01X304331Y1496063D02*
G03Y1503937I0J3937D01*
G01Y1496063D02*
G03Y1503937I0J3937D01*
G01X389213Y277843D02*
G03X396138Y264712I37662J11471D01*
G01X389213Y277843D02*
G03X396138Y264712I37662J11470D01*
G01X389213Y730599D02*
G03X396138Y717468I37662J11471D01*
G01X389213Y730599D02*
G03X396138Y717468I37662J11470D01*
G01X389213Y1183355D02*
G03X396138Y1170224I37662J11471D01*
G01X389213Y1183355D02*
G03X396138Y1170224I37662J11470D01*
G01X477559Y1503937D02*
G03Y1496063I0J-3937D01*
G01X459449D02*
G03Y1503937I0J3937D01*
G01X489370D02*
X477559D01*
G01D02*
G03Y1496063I0J-3937D01*
G01X459449D02*
G03Y1503937I0J3937D01*
G01X489370D02*
X477559D01*
G01X489370Y1515748D02*
G03X485433Y1519685I-3937J0D01*
G01X489370Y1515748D02*
G03X485433Y1519685I-3937J0D01*
G01X501181D02*
G03X497244Y1515748I0J-3937D01*
G01X680512Y1519685D02*
X501181D01*
G01D02*
G03X497244Y1515748I0J-3937D01*
G01X680512Y1519685D02*
X501181D01*
G01X489370Y1515748D02*
Y1503937D01*
G01X493307Y1496063D02*
G03X497244Y1500000I0J3937D01*
G01Y1515748D02*
Y1500000D01*
G01X489370Y1515748D02*
Y1503937D01*
G01X493307Y1496063D02*
G03X497244Y1500000I0J3937D01*
G01Y1515748D02*
Y1500000D01*
G01X637244Y277843D02*
G03X644169Y264712I37662J11471D01*
G01X637244Y277843D02*
G03X644169Y264712I37662J11471D01*
G01X637244Y277843D02*
G03X617283I-9980J-3040D01*
G01X610358Y264712D02*
G03X617283Y277843I-30737J24602D01*
G01X637244D02*
G03X617283I-9980J-3040D01*
G01X610358Y264712D02*
G03X617283Y277843I-30737J24601D01*
G01X610358Y264712D02*
G03X644169I16906J-13531D01*
G01X610358D02*
G03X644169I16906J-13531D01*
G01X637244Y730599D02*
G03X644169Y717468I37662J11471D01*
G01X637244Y730599D02*
G03X644169Y717468I37662J11471D01*
G01X637244Y730599D02*
G03X617283I-9980J-3040D01*
G01X610358Y717468D02*
G03X617283Y730599I-30737J24601D01*
G01X637244D02*
G03X617283I-9980J-3040D01*
G01X610358Y717468D02*
G03X617283Y730599I-30737J24601D01*
G01X610358Y717468D02*
G03X644169I16906J-13531D01*
G01X610358D02*
G03X644169I16906J-13531D01*
G01X610358Y1170224D02*
G03X644169I16906J-13531D01*
G01X610358D02*
G03X644169I16906J-13531D01*
G01X637244Y1183355D02*
G03X644169Y1170224I37662J11471D01*
G01X637244Y1183355D02*
G03X644169Y1170224I37662J11471D01*
G01X637244Y1183355D02*
G03X617283I-9980J-3040D01*
G01X637244D02*
G03X617283I-9980J-3040D01*
G01X610358Y1170224D02*
G03X617283Y1183355I-30737J24602D01*
G01X610358Y1170224D02*
G03X617283Y1183355I-30737J24601D01*
G01X730339Y383610D02*
G03X764149I16905J-13531D01*
G01X730339Y383609D02*
G03X764150I16905J-13530D01*
G01X757225Y396741D02*
G03X764149Y383610I37663J11469D01*
G01X757224Y396741D02*
G03X764150Y383609I37662J11471D01*
G01X757225Y396741D02*
G03X737264I-9981J-3040D01*
G01X730339Y383610D02*
G03X737264Y396741I-30737J24602D01*
G01X757224D02*
G03X737264I-9980J-3041D01*
G01X730339Y383609D02*
G03X737264Y396741I-30738J24601D01*
G01X757225Y829811D02*
G03X764149Y816680I37663J11469D01*
G01X757224Y829811D02*
G03X764150Y816680I37662J11473D01*
G01X757225Y829811D02*
G03X737264I-9981J-3039D01*
G01X757224D02*
G03X737264I-9980J-3040D01*
G01X730339Y816680D02*
G03X737264Y829811I-30737J24602D01*
G01X730339Y816680D02*
G03X737264Y829811I-30737J24602D01*
G01X730339Y816680D02*
G03X764149I16905J-13531D01*
G01X730339D02*
G03X764150I16905J-13531D01*
G01X721850Y1519685D02*
G03X717913Y1515748I0J-3937D01*
G01X775591Y1519685D02*
X721850D01*
G01D02*
G03X717913Y1515748I0J-3937D01*
G01X775591Y1519685D02*
X721850D01*
G01X713976Y1505118D02*
G03X717913Y1509055I0J3937D01*
G01Y1515748D02*
Y1509055D01*
G01X713976Y1505118D02*
G03X717913Y1509055I0J3937D01*
G01Y1515748D02*
Y1509055D01*
G01X684449Y1515748D02*
G03X680512Y1519685I-3937J0D01*
G01X684449Y1515748D02*
G03X680512Y1519685I-3937J0D01*
G01X684449Y1509055D02*
Y1515748D01*
G01Y1509055D02*
G03X688386Y1505118I3937J0D01*
G01X713976D02*
X688386D01*
G01X684449Y1509055D02*
G03X688386Y1505118I3937J0D01*
G01D02*
X713976D01*
G01X684449Y1515748D02*
Y1509055D01*
G01X791339Y3937D02*
G03X795276Y0I3937J0D01*
G01D02*
X892317D01*
G01X791339Y3937D02*
Y23622D01*
G01Y3937D02*
G03X795276Y0I3937J0D01*
G01X791339Y3937D02*
Y23622D01*
G01X795276Y0D02*
X892317D01*
G01X783465Y54331D02*
G03X791339I3937J0D01*
G01X783465D02*
G03X791339I3937J0D01*
G01Y23622D02*
G03X783465I-3937J0D01*
G01X791339D02*
G03X783465I-3937J0D01*
G01X779528Y0D02*
G03X783465Y3937I0J3937D01*
G01X779528Y0D02*
G03X783465Y3937I0J3937D01*
G01X791339Y54331D02*
Y181890D01*
G01Y54331D02*
Y181890D01*
G01X783465Y3937D02*
Y185827D01*
G01Y3937D02*
Y185827D01*
G01X811024Y181890D02*
G03X822835Y193701I0J11811D01*
G01X791339Y181890D02*
X811024D01*
G01D02*
G03X822835Y193701I0J11811D01*
G01X791339Y181890D02*
X811024D01*
G01X787402Y189764D02*
G03X783465Y185827I0J-3937D01*
G01X787402Y189764D02*
G03X783465Y185827I0J-3937D01*
G01X811024Y189764D02*
G03X814961Y193701I0J3937D01*
G01X787402Y189764D02*
X811024D01*
G01D02*
G03X814961Y193701I0J3937D01*
G01X787402Y189764D02*
X811024D01*
G01X822835Y193701D02*
Y240157D01*
G01Y193701D02*
Y240157D01*
G01X814961Y193701D02*
Y244094D01*
G01Y193701D02*
Y244094D01*
G01X818898Y248031D02*
G03X814961Y244094I0J-3937D01*
G01X818898Y248031D02*
G03X814961Y244094I0J-3937D01*
G01X928098Y240157D02*
X822835D01*
G01X928098D02*
X822835D01*
G01X818898Y248031D02*
X1055118D01*
G01D02*
X818898D01*
G01X954331Y1503937D02*
X817323D01*
G01X954331D02*
X817323D01*
G01X791339Y1519685D02*
G03X787402Y1515748I0J-3937D01*
G01X791339Y1519685D02*
X980315D01*
G01X791339D02*
G03X787402Y1515748I0J-3937D01*
G01X791339Y1519685D02*
X980315D01*
G01X817323Y1503937D02*
G03Y1496063I0J-3937D01*
G01X799213D02*
G03Y1503937I0J3937D01*
G01D02*
X787402D01*
G01Y1515748D02*
Y1503937D01*
G01X799213D02*
X787402D01*
G01X817323D02*
G03Y1496063I0J-3937D01*
G01X799213D02*
G03Y1503937I0J3937D01*
G01X787402Y1515748D02*
Y1503937D01*
G01X779528Y1515748D02*
G03X775591Y1519685I-3937J0D01*
G01X779528Y1515748D02*
G03X775591Y1519685I-3937J0D01*
G01X779528Y1500000D02*
Y1515748D01*
G01Y1500000D02*
G03X783465Y1496063I3937J0D01*
G01X988189D02*
X783465D01*
G01X779528Y1500000D02*
G03X783465Y1496063I3937J0D01*
G01X988189D02*
X783465D01*
G01X779528Y1515748D02*
Y1500000D01*
G01X900191Y0D02*
G03X892317I-3937J0D01*
G01X896254D02*
Y-394D01*
G01Y0D02*
Y394D01*
G01X895762Y0D02*
X896746D01*
G01X900191D02*
G03X892317I-3937J0D01*
G01X900191D02*
X1212598D01*
G01X900191D02*
X1212598D01*
G01X953294Y248031D02*
G03Y240157I1J-3937D01*
G01X1051181D02*
X953294D01*
G01Y248031D02*
G03Y240157I1J-3937D01*
G01X928098D02*
G03Y248031I0J3937D01*
G01Y240157D02*
G03Y248031I0J3937D01*
G01X1051181Y240157D02*
X953294D01*
G01X971398Y718788D02*
G03X951437I-9980J-3040D01*
G01X944512Y705657D02*
G03X951437Y718788I-30737J24602D01*
G01X971398D02*
G03X951437I-9980J-3040D01*
G01X944512Y705657D02*
G03X951437Y718788I-30737J24602D01*
G01X944512Y705657D02*
G03X978323I16905J-13531D01*
G01X944512D02*
G03X978323I16905J-13531D01*
G01X944512Y974161D02*
G03X978323I16905J-13531D01*
G01X944512D02*
G03X978323I16905J-13531D01*
G01X971398Y987292D02*
G03X951437I-9980J-3040D01*
G01X944512Y974161D02*
G03X951437Y987292I-30737J24602D01*
G01X971398D02*
G03X951437I-9980J-3040D01*
G01X944512Y974161D02*
G03X951437Y987292I-30737J24602D01*
G01X954331Y1496063D02*
G03Y1503937I0J3937D01*
G01Y1496063D02*
G03Y1503937I0J3937D01*
G01X1051181Y193701D02*
G03X1062992Y181890I11811J0D01*
G01X1051181Y193701D02*
G03X1062992Y181890I11811J0D01*
G01X1051181Y240157D02*
Y193701D01*
G01Y240157D02*
Y193701D01*
G01X971398Y718788D02*
G03X978323Y705657I37662J11471D01*
G01X971398Y718788D02*
G03X978323Y705657I37662J11470D01*
G01X971398Y987292D02*
G03X978323Y974161I37662J11471D01*
G01X971398Y987292D02*
G03X978323Y974161I37662J11470D01*
G01X1059196Y1519685D02*
X996063D01*
G01X1059196D02*
X996063D01*
G01X984252Y1515748D02*
G03X980315Y1519685I-3937J0D01*
G01X984252Y1515748D02*
G03X980315Y1519685I-3937J0D01*
G01X996063D02*
G03X992126Y1515748I0J-3937D01*
G01X996063Y1519685D02*
G03X992126Y1515748I0J-3937D01*
G01X972441Y1503937D02*
G03Y1496063I0J-3937D01*
G01X984252Y1503937D02*
X972441D01*
G01X984252Y1515748D02*
Y1503937D01*
G01X972441D02*
G03Y1496063I0J-3937D01*
G01X988189D02*
G03X992126Y1500000I0J3937D01*
G01Y1515748D02*
Y1500000D01*
G01X984252Y1515748D02*
Y1503937D01*
G01D02*
X972441D01*
G01X988189Y1496063D02*
G03X992126Y1500000I0J3937D01*
G01Y1515748D02*
Y1500000D01*
G01X1133071Y189764D02*
G03Y181890I0J-3937D01*
G01D02*
X1216535D01*
G01X1133071D02*
X1216535D01*
G01X1133071Y189764D02*
G03Y181890I0J-3937D01*
G01X1102362D02*
G03Y189764I0J3937D01*
G01Y181890D02*
G03Y189764I0J3937D01*
G01X1062992Y181890D02*
X1102362D01*
G01X1062992D02*
X1102362D01*
G01X1059055Y244094D02*
G03X1055118Y248031I-3937J0D01*
G01X1059055Y244094D02*
G03X1055118Y248031I-3937J0D01*
G01X1059055Y244094D02*
Y193701D01*
G01Y244094D02*
Y193701D01*
G01X1062992Y189764D02*
X1220472D01*
G01X1059055Y193701D02*
G03X1062992Y189764I3937J0D01*
G01X1059055Y193701D02*
G03X1062992Y189764I3937J0D01*
G01D02*
X1220472D01*
G01X1085630Y1417323D02*
G03X1089567Y1421260I0J3937D01*
G01X1085630Y1417323D02*
G03X1089567Y1421260I0J3937D01*
G01X1072638D02*
G03X1076575Y1417322I3937J-1D01*
G01X1085630Y1417323D02*
X1076575D01*
G01X1072638Y1421260D02*
G03X1076575Y1417323I3937J0D01*
G01D02*
X1085630D01*
G01X1089567Y1506243D02*
Y1421260D01*
G01Y1506243D02*
Y1421260D01*
G01X1072638D02*
Y1506243D01*
G01D02*
Y1421260D01*
G01X1103009Y1519685D02*
G03X1100225Y1518532I0J-3937D01*
G01X1207283Y1519685D02*
X1103009D01*
G01D02*
G03X1100225Y1518532I0J-3937D01*
G01X1207283Y1519685D02*
X1103009D01*
G01X1090720Y1509027D02*
G03X1089567Y1506243I2784J-2784D01*
G01X1100225Y1518532D02*
X1090720Y1509027D01*
G01D02*
G03X1089567Y1506243I2784J-2784D01*
G01X1100225Y1518532D02*
X1090720Y1509027D01*
G01X1061980Y1518532D02*
G03X1059196Y1519685I-2784J-2784D01*
G01X1061980Y1518532D02*
G03X1059196Y1519685I-2784J-2784D01*
G01X1071485Y1509027D02*
X1061980Y1518532D01*
G01X1072638Y1506243D02*
G03X1071485Y1509027I-3937J0D01*
G01X1072638Y1506243D02*
G03X1071485Y1509027I-3937J0D01*
G01X1061980Y1518532D02*
X1071485Y1509027D01*
G01X1216535Y54331D02*
G03X1224409I3937J0D01*
G01X1216535D02*
Y181890D01*
G01Y54331D02*
Y181890D01*
G01Y54331D02*
G03X1224409I3937J0D01*
G01Y23622D02*
G03X1216535I-3937J0D01*
G01X1224409D02*
G03X1216535I-3937J0D01*
G01X1212598Y0D02*
G03X1216535Y3937I0J3937D01*
G01D02*
Y23622D01*
G01X1212598Y0D02*
G03X1216535Y3937I0J3937D01*
G01X1224409D02*
G03X1228346Y0I3937J0D01*
G01X1224409Y185827D02*
Y3937D01*
G01X1216535D02*
Y23622D01*
G01X1224409Y3937D02*
G03X1228346Y0I3937J0D01*
G01X1224409Y3937D02*
Y185827D01*
G01X1228346Y0D02*
X1930906D01*
G01X1228346D02*
X1930906D01*
G01X1224409Y185827D02*
G03X1220472Y189764I-3937J0D01*
G01X1224409Y185827D02*
G03X1220472Y189764I-3937J0D01*
G01X1164984Y383609D02*
G03X1198795I16906J-13530D01*
G01X1164984D02*
G03X1198795I16906J-13530D01*
G01X1191870Y396741D02*
G03X1198795Y383610I37662J11471D01*
G01X1191870Y396741D02*
G03X1198795Y383609I37663J11469D01*
G01X1191870Y396741D02*
G03X1171909I-9980J-3040D01*
G01X1164984Y383610D02*
G03X1171909Y396741I-30737J24602D01*
G01X1191870D02*
G03X1171909I-9980J-3040D01*
G01X1164984Y383609D02*
G03X1171909Y396741I-30737J24601D01*
G01X1164984Y974161D02*
G03X1198795I16906J-13531D01*
G01X1164984D02*
G03X1198795I16906J-13531D01*
G01X1191870Y987292D02*
G03X1198795Y974161I37662J11471D01*
G01X1191870Y987292D02*
G03X1198795Y974161I37662J11471D01*
G01X1191870Y987292D02*
G03X1171909I-9980J-3040D01*
G01X1164984Y974161D02*
G03X1171909Y987292I-30737J24602D01*
G01X1191870D02*
G03X1171909I-9980J-3040D01*
G01X1164984Y974161D02*
G03X1171909Y987292I-30737J24601D01*
G01X1240748Y1505118D02*
G03X1244685Y1509055I0J3937D01*
G01X1240748Y1505118D02*
G03X1244685Y1509055I0J3937D01*
G01X1211220Y1515748D02*
G03X1207283Y1519685I-3937J0D01*
G01X1211220Y1515748D02*
G03X1207283Y1519685I-3937J0D01*
G01X1211220Y1509055D02*
Y1515748D01*
G01Y1509055D02*
G03X1215157Y1505118I3937J0D01*
G01X1240748D02*
X1215157D01*
G01X1211220Y1509055D02*
G03X1215157Y1505118I3937J0D01*
G01D02*
X1240748D01*
G01X1211220Y1515748D02*
Y1509055D01*
G01X1311851Y277843D02*
G03X1318775Y264712I37663J11469D01*
G01X1311850Y277843D02*
G03X1318776Y264712I37661J11473D01*
G01X1311851Y277843D02*
G03X1291890I-9980J-3040D01*
G01X1284965Y264712D02*
G03X1291890Y277843I-30737J24602D01*
G01X1311850D02*
G03X1291890I-9980J-3040D01*
G01X1284965Y264712D02*
G03X1291890Y277843I-30737J24602D01*
G01X1284965Y264712D02*
G03X1318775I16905J-13531D01*
G01X1284965D02*
G03X1318776I16906J-13531D01*
G01X1311851Y730599D02*
G03X1318775Y717468I37663J11469D01*
G01X1311850Y730599D02*
G03X1318776Y717468I37661J11473D01*
G01X1311851Y730599D02*
G03X1291890I-9980J-3040D01*
G01X1284965Y717468D02*
G03X1291891Y730599I-30736J24604D01*
G01X1311850D02*
G03X1291890I-9980J-3040D01*
G01X1284965Y717468D02*
G03X1291890Y730599I-30737J24602D01*
G01X1284965Y717468D02*
G03X1318775I16905J-13531D01*
G01X1284965D02*
G03X1318776I16906J-13531D01*
G01X1284965Y1170224D02*
G03X1318775I16905J-13531D01*
G01X1284965D02*
G03X1318776I16906J-13531D01*
G01X1311851Y1183355D02*
G03X1318775Y1170224I37663J11469D01*
G01X1311850Y1183355D02*
G03X1318776Y1170224I37661J11473D01*
G01X1311851Y1183355D02*
G03X1291890I-9980J-3040D01*
G01X1311850D02*
G03X1291890I-9980J-3040D01*
G01X1284965Y1170224D02*
G03X1291890Y1183355I-30737J24602D01*
G01X1284965Y1170224D02*
G03X1291890Y1183355I-30737J24602D01*
G01X1248622Y1519685D02*
G03X1244685Y1515748I0J-3937D01*
G01X1427953Y1519685D02*
X1248622D01*
G01D02*
G03X1244685Y1515748I0J-3937D01*
G01X1427953Y1519685D02*
X1248622D01*
G01X1244685Y1515748D02*
Y1509055D01*
G01Y1515748D02*
Y1509055D01*
G01X1431890Y1515748D02*
G03X1427953Y1519685I-3937J0D01*
G01X1431890Y1515748D02*
G03X1427953Y1519685I-3937J0D01*
G01X1431890Y1500000D02*
Y1515748D01*
G01Y1500000D02*
G03X1435827Y1496063I3937J0D01*
G01X1431890Y1500000D02*
G03X1435827Y1496063I3937J0D01*
G01X1431890Y1515748D02*
Y1500000D01*
G01X1532996Y264712D02*
G03X1566807I16906J-13531D01*
G01X1532996D02*
G03X1566807I16906J-13531D01*
G01X1532996Y717468D02*
G03X1566807I16906J-13531D01*
G01X1532996D02*
G03X1566807I16906J-13531D01*
G01X1532996Y1170224D02*
G03X1566807I16906J-13531D01*
G01X1532996D02*
G03X1566807I16906J-13531D01*
G01X1469685Y1503937D02*
G03Y1496063I0J-3937D01*
G01X1451575D02*
G03Y1503937I0J3937D01*
G01X1606693D02*
X1469685D01*
G01X1606693D02*
X1469685D01*
G01D02*
G03Y1496063I0J-3937D01*
G01X1451575D02*
G03Y1503937I0J3937D01*
G01X1443701Y1519685D02*
G03X1439764Y1515748I0J-3937D01*
G01X1443701Y1519685D02*
X1632677D01*
G01X1443701D02*
G03X1439764Y1515748I0J-3937D01*
G01X1443701Y1519685D02*
X1632677D01*
G01X1451575Y1503937D02*
X1439764D01*
G01Y1515748D02*
Y1503937D01*
G01X1451575D02*
X1439764D01*
G01X1640551Y1496063D02*
X1435827D01*
G01X1439764Y1515748D02*
Y1503937D01*
G01X1640551Y1496063D02*
X1435827D01*
G01X1559882Y277843D02*
G03X1566807Y264712I37662J11471D01*
G01X1559882Y277843D02*
G03X1539921I-9980J-3040D01*
G01X1559882D02*
G03X1566807Y264712I37662J11471D01*
G01X1559882Y277843D02*
G03X1539921I-9980J-3040D01*
G01X1532996Y264712D02*
G03X1539921Y277843I-30737J24602D01*
G01X1532996Y264712D02*
G03X1539921Y277843I-30737J24602D01*
G01X1559882Y730599D02*
G03X1566807Y717468I37662J11471D01*
G01X1559882Y730599D02*
G03X1539921I-9980J-3040D01*
G01X1559882D02*
G03X1566807Y717468I37662J11471D01*
G01X1559882Y730599D02*
G03X1539921I-9980J-3040D01*
G01X1532996Y717468D02*
G03X1539921Y730599I-30737J24601D01*
G01X1532996Y717468D02*
G03X1539921Y730599I-30737J24601D01*
G01X1559882Y1183355D02*
G03X1539921I-9980J-3040D01*
G01X1559882D02*
G03X1539921I-9980J-3040D01*
G01X1559882D02*
G03X1566807Y1170224I37662J11471D01*
G01X1559882Y1183355D02*
G03X1566807Y1170224I37662J11471D01*
G01X1532996D02*
G03X1539921Y1183355I-30737J24602D01*
G01X1532996Y1170224D02*
G03X1539921Y1183355I-30737J24601D01*
G01X1636614Y1503937D02*
X1624803D01*
G01X1636614D02*
X1624803D01*
G01D02*
G03Y1496063I0J-3937D01*
G01X1606693D02*
G03Y1503937I0J3937D01*
G01X1624803D02*
G03Y1496063I0J-3937D01*
G01X1606693D02*
G03Y1503937I0J3937D01*
G01X1636614Y1515748D02*
G03X1632677Y1519685I-3937J0D01*
G01X1636614Y1515748D02*
G03X1632677Y1519685I-3937J0D01*
G01X1648425D02*
G03X1644488Y1515748I0J-3937D01*
G01X1827756Y1519685D02*
X1648425D01*
G01D02*
G03X1644488Y1515748I0J-3937D01*
G01X1827756Y1519685D02*
X1648425D01*
G01X1636614Y1515748D02*
Y1503937D01*
G01X1640551Y1496063D02*
G03X1644488Y1500000I0J3937D01*
G01Y1515748D02*
Y1500000D01*
G01X1636614Y1515748D02*
Y1503937D01*
G01X1640551Y1496063D02*
G03X1644488Y1500000I0J3937D01*
G01Y1515748D02*
Y1500000D01*
G01X1807914Y277843D02*
G03X1814838Y264712I37663J11469D01*
G01X1807913Y277843D02*
G03X1814839Y264712I37661J11473D01*
G01X1807914Y277843D02*
G03X1787953I-9980J-3040D01*
G01X1781028Y264712D02*
G03X1787953Y277843I-30737J24602D01*
G01X1807913D02*
G03X1787953I-9980J-3040D01*
G01X1781028Y264712D02*
G03X1787953Y277843I-30737J24602D01*
G01X1781028Y264712D02*
G03X1814839I16906J-13531D01*
G01X1781028D02*
G03X1814839I16906J-13531D01*
G01X1807914Y730599D02*
G03X1814838Y717468I37663J11469D01*
G01X1807913Y730599D02*
G03X1814839Y717468I37661J11473D01*
G01X1807914Y730599D02*
G03X1787953I-9980J-3040D01*
G01X1781028Y717468D02*
G03X1787954Y730599I-30736J24604D01*
G01X1807913D02*
G03X1787953I-9980J-3040D01*
G01X1781028Y717468D02*
G03X1787953Y730599I-30737J24602D01*
G01X1781028Y717468D02*
G03X1814838I16905J-13531D01*
G01X1781028D02*
G03X1814839I16906J-13531D01*
G01X1781028Y1170224D02*
G03X1814838I16905J-13531D01*
G01X1781028D02*
G03X1814839I16906J-13531D01*
G01X1807914Y1183355D02*
G03X1814838Y1170224I37662J11468D01*
G01X1807913Y1183355D02*
G03X1814839Y1170224I37661J11473D01*
G01X1807914Y1183355D02*
G03X1787953I-9980J-3040D01*
G01X1807913D02*
G03X1787953I-9980J-3040D01*
G01X1781028Y1170224D02*
G03X1787953Y1183355I-30737J24602D01*
G01X1781028Y1170224D02*
G03X1787953Y1183355I-30737J24602D01*
G01X1869094Y1519685D02*
G03X1865157Y1515748I0J-3937D01*
G01X1919094Y1519685D02*
X1869094D01*
G01D02*
G03X1865157Y1515748I0J-3937D01*
G01X1919094Y1519685D02*
X1869094D01*
G01X1865157Y1515748D02*
Y1509055D01*
G01Y1515748D02*
Y1509055D01*
G01X1861220Y1505118D02*
X1835630D01*
G01X1861220D02*
G03X1865157Y1509055I0J3937D01*
G01X1861220Y1505118D02*
G03X1865157Y1509055I0J3937D01*
G01X1835630Y1505118D02*
X1861220D01*
G01X1831693Y1515748D02*
G03X1827756Y1519685I-3937J0D01*
G01X1831693Y1515748D02*
G03X1827756Y1519685I-3937J0D01*
G01X1831693Y1509055D02*
Y1515748D01*
G01Y1509055D02*
G03X1835630Y1505118I3937J0D01*
G01X1831693Y1509055D02*
G03X1835630Y1505118I3937J0D01*
G01X1831693Y1515748D02*
Y1509055D01*
G01X1930906Y0D02*
G03X1934843Y3937I0J3937D01*
G01X1930906Y0D02*
G03X1934843Y3937I0J3937D01*
G01D02*
Y1456693D01*
G01Y3937D02*
Y1456693D01*
G01X1930906Y1460630D02*
X1926969D01*
G01X1934843Y1456693D02*
G03X1930906Y1460630I-3937J0D01*
G01X1934843Y1456693D02*
G03X1930906Y1460630I-3937J0D01*
G01D02*
X1926969D01*
G01X1923031Y1515748D02*
G03X1919094Y1519685I-3937J0D01*
G01X1923031Y1515748D02*
G03X1919094Y1519685I-3937J0D01*
G01X1923031Y1464567D02*
Y1515748D01*
G01Y1464567D02*
G03X1926969Y1460630I3937J0D01*
G01X1923031Y1464567D02*
G03X1926969Y1460630I3937J0D01*
G01X1923031Y1515748D02*
Y1464567D01*
G54D12*
G01X790078Y464028D02*
X787971Y461921D01*
G01X810351Y464028D02*
X790078D01*
G01X875681Y529358D02*
X810351Y464028D01*
G01X811108Y461921D02*
X876519Y527332D01*
G01X791971Y461921D02*
X811108D01*
G01X790374Y468524D02*
X787971Y466121D01*
G01X809119Y468524D02*
X790374D01*
G01X874003Y533408D02*
X809119Y468524D01*
G01X809580Y466121D02*
X874842Y531383D01*
G01X791971Y466121D02*
X809580D01*
G01X812636Y457721D02*
X878196Y523281D01*
G01X791971Y457721D02*
X812636D01*
G01X811849Y459798D02*
X877357Y525306D01*
G01X790048Y459798D02*
X811849D01*
G01X787971Y457721D02*
X790048Y459798D01*
G01X949544Y344693D02*
X974451Y369600D01*
G01X914878Y344693D02*
X949544D01*
G01X896300Y326115D02*
X914878Y344693D01*
G01X896300Y313383D02*
Y326115D01*
G01X895300Y312383D02*
X896300Y313383D01*
G01X895300Y308637D02*
Y312383D01*
G01X897638Y306299D02*
X895300Y308637D01*
G01X916637Y340643D02*
X909236Y333242D01*
G01X951751Y340643D02*
X916637D01*
G01X976363Y365255D02*
X951751Y340643D01*
G01X906486Y333437D02*
Y330524D01*
G01X915717Y342668D02*
X906486Y333437D01*
G01X950912Y342668D02*
X915717D01*
G01X975524Y367280D02*
X950912Y342668D01*
G01X952590Y338618D02*
X977202Y363230D01*
G01X921607Y338618D02*
X952590D01*
G01X900125Y317136D02*
X921607Y338618D01*
G01X900125Y298144D02*
Y317136D01*
G01X904725Y293544D02*
X900125Y298144D01*
G01X904725Y291338D02*
Y293544D01*
G01X953429Y336593D02*
X978041Y361205D01*
G01X922446Y336593D02*
X953429D01*
G01X902200Y316347D02*
X922446Y336593D01*
G01X902200Y299300D02*
Y316347D01*
G01X904650Y296850D02*
X902200Y299300D01*
G01X904725Y296850D02*
X904650D01*
G01X950843Y375343D02*
Y378827D01*
G01X927703Y352203D02*
X950843Y375343D01*
G01X927509Y352203D02*
X927703D01*
G01X925675Y350369D02*
X927509Y352203D01*
G01X912526Y350369D02*
X925675D01*
G01X888100Y325943D02*
X912526Y350369D01*
G01X888100Y303800D02*
Y325943D01*
G01X890552Y301348D02*
X888100Y303800D01*
G01X890552Y301181D02*
Y301348D01*
G01X954100Y334400D02*
X978880Y359180D01*
G01X925440Y334400D02*
X954100D01*
G01X907200Y316160D02*
X925440Y334400D01*
G01X907200Y313498D02*
Y316160D01*
G01X904725Y311023D02*
X907200Y313498D01*
G01X926564Y332300D02*
X1001800D01*
G01X909275Y315011D02*
X926564Y332300D01*
G01X909275Y312638D02*
Y315011D01*
G01X909226Y312589D02*
X909275Y312638D01*
G01X909226Y312026D02*
Y312589D01*
G01X904725Y307525D02*
X909226Y312026D01*
G01X904725Y305512D02*
Y307525D01*
G01X877357Y529358D02*
X875681D01*
G01X877358Y529357D02*
X877357Y529358D01*
G01X879034Y529357D02*
X877358D01*
G01X879035Y529356D02*
X879034Y529357D01*
G01X898590Y529356D02*
X879035D01*
G01X933649Y564415D02*
X898590Y529356D01*
G01X966091Y564415D02*
X933649D01*
G01X934995Y562390D02*
X966930D01*
G01X899936Y527331D02*
X934995Y562390D01*
G01X878196Y527331D02*
X899936D01*
G01X878195Y527332D02*
X878196Y527331D01*
G01X876519Y527332D02*
X878195D01*
G01X879035Y533408D02*
X874003D01*
G01X879036Y533407D02*
X879035Y533408D01*
G01X880713Y533407D02*
X879036D01*
G01X880714Y533406D02*
X880713Y533407D01*
G01X892821Y533406D02*
X880714D01*
G01X927912Y568497D02*
X892821Y533406D01*
G01X960468Y568497D02*
X927912D01*
G01X930177Y566456D02*
X964012D01*
G01X895102Y531381D02*
X930177Y566456D01*
G01X879875Y531381D02*
X895102D01*
G01X879874Y531382D02*
X879875Y531381D01*
G01X878197Y531382D02*
X879874D01*
G01X878196Y531383D02*
X878197Y531382D01*
G01X874842Y531383D02*
X878196D01*
G01X951953Y544759D02*
X961160Y553966D01*
G01X923179Y544759D02*
X951953D01*
G01X901701Y523281D02*
X923179Y544759D01*
G01X878196Y523281D02*
X901701D01*
G01X935834Y560365D02*
X967769D01*
G01X918676Y543207D02*
X935834Y560365D01*
G01X918676Y543120D02*
Y543207D01*
G01X900862Y525306D02*
X918676Y543120D01*
G01X877357Y525306D02*
X900862D01*
G01X988026Y369600D02*
X1020508Y402082D01*
G01X974451Y369600D02*
X988026D01*
G01X989571Y365255D02*
X976363D01*
G01X1023380Y399064D02*
X989571Y365255D01*
G01X988724Y367280D02*
X975524D01*
G01X1022646Y401202D02*
X988724Y367280D01*
G01X990719Y363230D02*
X1071421Y443932D01*
G01X977202Y363230D02*
X990719D01*
G01X992166Y361205D02*
X1021469Y390508D01*
G01X978041Y361205D02*
X992166D01*
G01X993620Y359180D02*
X1059563Y425123D01*
G01X978880Y359180D02*
X993620D01*
G01X1001800Y332300D02*
X1074279Y404779D01*
G01X1021766Y403340D02*
X1047434Y429008D01*
G01X1021761Y403340D02*
X1021766D01*
G01X1020508Y402087D02*
X1021761Y403340D01*
G01X1020508Y402082D02*
Y402087D01*
G01X1047434Y429008D02*
X1102677Y484251D01*
G01X1023531Y399064D02*
X1023380D01*
G01X1024784Y400317D02*
X1023531Y399064D01*
G01X1024784Y400468D02*
Y400317D01*
G01X1038179Y413863D02*
X1024784Y400468D01*
G01X1038179Y413863D02*
X1108416Y484100D01*
G01X1049572Y428128D02*
X1107569Y486125D01*
G01X1049572Y428123D02*
Y428128D01*
G01X1048319Y426870D02*
X1049572Y428123D01*
G01X1048314Y426870D02*
X1048319D01*
G01X1037445Y416001D02*
X1048314Y426870D01*
G01X1037294Y416001D02*
X1037445D01*
G01X1036041Y414748D02*
X1037294Y416001D01*
G01X1036041Y414597D02*
Y414748D01*
G01X1022646Y401202D02*
X1036041Y414597D01*
G01X1021469Y390508D02*
X1099084Y468123D01*
G01X1060985Y659309D02*
X966091Y564415D01*
G01X966930Y562390D02*
X1064220Y659680D01*
G01X1055781Y663810D02*
X960468Y568497D01*
G01X964012Y566456D02*
X1057806Y660250D01*
G01X972452Y553966D02*
X1071179Y652693D01*
G01X961160Y553966D02*
X972452D01*
G01X967769Y560365D02*
X1067554Y660150D01*
G01X1143420Y475980D02*
Y472900D01*
G01X1120323Y470323D02*
X1128125Y478125D01*
G01X1097812Y470323D02*
X1120323D01*
G01X1071421Y443932D02*
X1097812Y470323D01*
G01X1141400Y470190D02*
X1139590Y468380D01*
G01X1141400Y472038D02*
Y470190D01*
G01X1141382Y472056D02*
X1141400Y472038D01*
G01X1141382Y474754D02*
Y472056D01*
G01X1140036Y476100D02*
X1141382Y474754D01*
G01X1122123Y468123D02*
X1130100Y476100D01*
G01X1099084Y468123D02*
X1122123D01*
G01X1126601Y464111D02*
X1135310Y472820D01*
G01X1098551Y464111D02*
X1126601D01*
G01X1059563Y425123D02*
X1098551Y464111D01*
G01X1135410Y468380D02*
X1074279Y407249D01*
G01Y404779D02*
Y407249D01*
G01X1102677Y484251D02*
Y487116D01*
G01X1147487Y484100D02*
X1149964Y481623D01*
G01X1108416Y484100D02*
X1147487D01*
G01X1107569Y486125D02*
X1149875D01*
G01X1141275Y478125D02*
X1143420Y475980D01*
G01X1128125Y478125D02*
X1141275D01*
G01X1130100Y476100D02*
X1140036D01*
G01X1060985Y683323D02*
Y659309D01*
G01X1064220Y659680D02*
Y683747D01*
G01X1055781Y681052D02*
Y663810D01*
G01X1057806Y660250D02*
Y680213D01*
G01X1071179Y652693D02*
Y682315D01*
G01X1067554Y660150D02*
Y694447D01*
G01X1059927Y684381D02*
X1060985Y683323D01*
G01X1059927Y688329D02*
Y684381D01*
G01X1064220Y683747D02*
X1064216Y683751D01*
G01X1117760Y738050D02*
X1153988D01*
G01X1114493Y741317D02*
X1117760Y738050D01*
G01X1113530Y741317D02*
X1114493D01*
G01X1055788Y681059D02*
X1055781Y681052D01*
G01X1055788Y681077D02*
Y681059D01*
G01X1056104Y681393D02*
X1055788Y681077D01*
G01X1056104Y697088D02*
Y681393D01*
G01X1056116Y697100D02*
X1056104Y697088D01*
G01X1121555Y743830D02*
X1152102D01*
G01X1119042Y741317D02*
X1121555Y743830D01*
G01X1057806Y680213D02*
X1057826Y680233D01*
G01X1112091Y745905D02*
X1152891D01*
G01X1109593Y748403D02*
X1112091Y745905D01*
G01X1122152Y758600D02*
X1158018D01*
G01X1119042Y755490D02*
X1122152Y758600D01*
G01X1116044Y752976D02*
X1157255D01*
G01X1113530Y755490D02*
X1116044Y752976D01*
G01X1117603Y750901D02*
X1154899D01*
G01X1115105Y748403D02*
X1117603Y750901D01*
G01X1149875Y486125D02*
X1150900Y485100D01*
G01X1192568Y719895D02*
X1212587D01*
G01X1172143D02*
X1192568D01*
G01X1153988Y738050D02*
X1172143Y719895D01*
G01X1171837Y724095D02*
X1198213D01*
G01X1152102Y743830D02*
X1171837Y724095D01*
G01X1198213D02*
X1212587D01*
G01X1192853Y728295D02*
X1212587D01*
G01X1171841D02*
X1192853D01*
G01X1154246Y745890D02*
X1171841Y728295D01*
G01X1152906Y745890D02*
X1154246D01*
G01X1152891Y745905D02*
X1152906Y745890D01*
G01X1212587Y740895D02*
X1198184D01*
G01X1175723D02*
X1198184D01*
G01X1158018Y758600D02*
X1175723Y740895D01*
G01X1192158Y736695D02*
X1212587D01*
G01X1173536D02*
X1192158D01*
G01X1157255Y752976D02*
X1173536Y736695D01*
G01X1197842Y732495D02*
X1212587D01*
G01X1173305D02*
X1197842D01*
G01X1154899Y750901D02*
X1173305Y732495D01*
M02*
